FILE_TYPE = MACRO_DRAWING;
SET COLOR_WIRE YELLOW;
SET COLOR_PROP MONO;
SET COLOR_DOT WHITE;
SET COLOR_ARC YELLOW;
SET COLOR_BODY GREEN;
SET COLOR_NOTE MONO;
SET PROP_DISPLAY VALUE;
SET PAGE_NUMBER P72;
FORCEADD PVDDQ_GHJ..1
(-7325 4250);
FORCEPROP 3 LASTPIN (-7325 4200) SIG_NAME PVDDQ_GHJ\g
J 0
(-7315 4210);
DISPLAY 0.659574 (-7315 4210);
PAINT MONO (-7315 4210);
DISPLAY INVISIBLE (-7315 4210);
FORCEPROP 1 LAST VOLTAGE 1.2V
J 0
(-7370 4207);
DISPLAY 0.340426 (-7370 4207);
PAINT SKYBLUE (-7370 4207);
DISPLAY INVISIBLE (-7370 4207);
FORCEPROP 2 LAST CDS_LIB mstr_symbols
J 0
(-7325 4250);
PAINT ORANGE (-7325 4250);
DISPLAY INVISIBLE (-7325 4250);
FORCEPROP 1 LAST BODY_TYPE PLUMBING
J 0
(-7370 4207);
DISPLAY 0.340426 (-7370 4207);
PAINT GREEN (-7370 4207);
DISPLAY INVISIBLE (-7370 4207);
FORCEPROP 1 LAST PATH I14
J 0
(-7275 4275);
DISPLAY 0.872340 (-7275 4275);
PAINT AQUA (-7275 4275);
DISPLAY INVISIBLE (-7275 4275);
FORCEPROP 1 LAST HDL_POWER PVDDQ_GHJ
J 1
(-7325 4300);
DISPLAY 0.872340 (-7325 4300);
PAINT GREEN (-7325 4300);
DISPLAY INVISIBLE (-7325 4300);
FORCEADD PVDDQ_KLM..1
(-5050 4250);
FORCEPROP 3 LASTPIN (-5050 4200) SIG_NAME PVDDQ_KLM\g
J 0
(-5040 4210);
DISPLAY 0.659574 (-5040 4210);
PAINT MONO (-5040 4210);
DISPLAY INVISIBLE (-5040 4210);
FORCEPROP 1 LAST VOLTAGE 1.2V
J 0
(-5095 4207);
DISPLAY 0.340426 (-5095 4207);
PAINT SKYBLUE (-5095 4207);
DISPLAY INVISIBLE (-5095 4207);
FORCEPROP 2 LAST CDS_LIB mstr_symbols
J 0
(-5050 4250);
PAINT ORANGE (-5050 4250);
DISPLAY INVISIBLE (-5050 4250);
FORCEPROP 1 LAST BODY_TYPE PLUMBING
J 0
(-5095 4207);
DISPLAY 0.340426 (-5095 4207);
PAINT GREEN (-5095 4207);
DISPLAY INVISIBLE (-5095 4207);
FORCEPROP 1 LAST PATH I15
J 0
(-5000 4275);
DISPLAY 0.872340 (-5000 4275);
PAINT AQUA (-5000 4275);
DISPLAY INVISIBLE (-5000 4275);
FORCEPROP 1 LAST HDL_POWER PVDDQ_KLM
J 1
(-5050 4300);
DISPLAY 0.872340 (-5050 4300);
PAINT GREEN (-5050 4300);
DISPLAY INVISIBLE (-5050 4300);
FORCEADD PVCCIO_CPU1..1
(-3850 4850);
FORCEPROP 3 LASTPIN (-3850 4800) SIG_NAME PVCCIO_CPU1\g
J 0
(-3840 4810);
DISPLAY 0.659574 (-3840 4810);
PAINT MONO (-3840 4810);
DISPLAY INVISIBLE (-3840 4810);
FORCEPROP 1 LAST VOLTAGE 1.1V
J 0
(-3895 4807);
DISPLAY 0.340426 (-3895 4807);
PAINT SKYBLUE (-3895 4807);
DISPLAY INVISIBLE (-3895 4807);
FORCEPROP 2 LAST CDS_LIB mstr_symbols
J 0
(-3850 4850);
PAINT ORANGE (-3850 4850);
DISPLAY INVISIBLE (-3850 4850);
FORCEPROP 1 LAST BODY_TYPE PLUMBING
J 0
(-3895 4807);
DISPLAY 0.340426 (-3895 4807);
PAINT GREEN (-3895 4807);
DISPLAY INVISIBLE (-3895 4807);
FORCEPROP 1 LAST PATH I17
J 0
(-3800 4875);
DISPLAY 0.872340 (-3800 4875);
PAINT AQUA (-3800 4875);
DISPLAY INVISIBLE (-3800 4875);
FORCEPROP 1 LAST HDL_POWER PVCCIO_CPU1
J 1
(-3850 4900);
DISPLAY 0.872340 (-3850 4900);
PAINT GREEN (-3850 4900);
DISPLAY INVISIBLE (-3850 4900);
FORCEADD PVCCIO_CPU1..1
(-900 1050);
FORCEPROP 3 LASTPIN (-900 1000) SIG_NAME PVCCIO_CPU1\g
J 0
(-890 1010);
DISPLAY 0.659574 (-890 1010);
PAINT MONO (-890 1010);
DISPLAY INVISIBLE (-890 1010);
FORCEPROP 1 LAST VOLTAGE 1.1V
J 0
(-945 1007);
DISPLAY 0.340426 (-945 1007);
PAINT SKYBLUE (-945 1007);
DISPLAY INVISIBLE (-945 1007);
FORCEPROP 2 LAST CDS_LIB mstr_symbols
J 0
(-900 1050);
PAINT ORANGE (-900 1050);
DISPLAY INVISIBLE (-900 1050);
FORCEPROP 1 LAST BODY_TYPE PLUMBING
J 0
(-945 1007);
DISPLAY 0.340426 (-945 1007);
PAINT GREEN (-945 1007);
DISPLAY INVISIBLE (-945 1007);
FORCEPROP 1 LAST PATH I18
J 0
(-850 1075);
DISPLAY 0.872340 (-850 1075);
PAINT AQUA (-850 1075);
DISPLAY INVISIBLE (-850 1075);
FORCEPROP 1 LAST HDL_POWER PVCCIO_CPU1
J 1
(-900 1100);
DISPLAY 0.872340 (-900 1100);
PAINT GREEN (-900 1100);
DISPLAY INVISIBLE (-900 1100);
FORCEADD PVSA_CPU1..1
(-1600 4825);
FORCEPROP 3 LASTPIN (-1600 4775) SIG_NAME PVSA_CPU1\g
J 0
(-1590 4785);
DISPLAY 0.659574 (-1590 4785);
PAINT MONO (-1590 4785);
DISPLAY INVISIBLE (-1590 4785);
FORCEPROP 1 LAST VOLTAGE 1.1V
J 0
(-1645 4782);
DISPLAY 0.340426 (-1645 4782);
PAINT SKYBLUE (-1645 4782);
DISPLAY INVISIBLE (-1645 4782);
FORCEPROP 2 LAST CDS_LIB mstr_symbols
J 0
(-1600 4825);
PAINT ORANGE (-1600 4825);
DISPLAY INVISIBLE (-1600 4825);
FORCEPROP 1 LAST BODY_TYPE PLUMBING
J 0
(-1645 4782);
DISPLAY 0.340426 (-1645 4782);
PAINT GREEN (-1645 4782);
DISPLAY INVISIBLE (-1645 4782);
FORCEPROP 1 LAST PATH I22
J 0
(-1550 4850);
DISPLAY 0.872340 (-1550 4850);
PAINT AQUA (-1550 4850);
DISPLAY INVISIBLE (-1550 4850);
FORCEPROP 1 LAST HDL_POWER PVSA_CPU1
J 1
(-1600 4875);
DISPLAY 0.872340 (-1600 4875);
PAINT GREEN (-1600 4875);
DISPLAY INVISIBLE (-1600 4875);
FORCEADD GND..1
(-525 775);
FORCEPROP 3 LASTPIN (-525 825) SIG_NAME GND\g
J 0
(-515 835);
DISPLAY 0.659574 (-515 835);
PAINT MONO (-515 835);
DISPLAY INVISIBLE (-515 835);
FORCEPROP 1 LAST VOLTAGE 0.0V
J 0
(-570 732);
DISPLAY 0.340426 (-570 732);
PAINT SKYBLUE (-570 732);
DISPLAY INVISIBLE (-570 732);
FORCEPROP 2 LAST CDS_LIB mstr_symbols
J 0
(-525 775);
PAINT ORANGE (-525 775);
DISPLAY INVISIBLE (-525 775);
FORCEPROP 1 LAST SIZE 1B
J 0
(-450 725);
DISPLAY 1.170213 (-450 725);
PAINT AQUA (-450 725);
DISPLAY INVISIBLE (-450 725);
FORCEPROP 1 LAST BODY_TYPE PLUMBING
J 0
(-570 732);
DISPLAY 0.340426 (-570 732);
PAINT GREEN (-570 732);
DISPLAY INVISIBLE (-570 732);
FORCEPROP 1 LAST PATH I23
J 0
(-450 775);
DISPLAY 0.872340 (-450 775);
PAINT AQUA (-450 775);
DISPLAY INVISIBLE (-450 775);
FORCEPROP 1 LAST HDL_POWER GND
J 0
(-525 925);
DISPLAY 1.170213 (-525 925);
PAINT GREEN (-525 925);
DISPLAY INVISIBLE (-525 925);
FORCEADD CAP..1
(-525 1075);
FORCEPROP 1 LAST LOCATION C3D3
J 0
(-475 1175);
DISPLAY 0.617021 (-475 1175);
PAINT AQUA (-475 1175);
FORCEPROP 1 LAST PART_NUMBER E15431-001
J 0
(-475 925);
DISPLAY 0.617021 (-475 925);
PAINT BLUE (-475 925);
FORCEPROP 1 LAST VALUE 10UF
J 0
(-475 1125);
DISPLAY 0.617021 (-475 1125);
PAINT SKYBLUE (-475 1125);
FORCEPROP 1 LAST TOLERANCE 20%
J 0
(-475 1025);
DISPLAY 0.617021 (-475 1025);
PAINT SKYBLUE (-475 1025);
FORCEPROP 1 LAST PACK_TYPE 0603LF
J 0
(-475 875);
DISPLAY 0.617021 (-475 875);
PAINT SKYBLUE (-475 875);
FORCEPROP 1 LAST VOLTAGE 4V
J 0
(-475 1075);
DISPLAY 0.617021 (-475 1075);
PAINT SKYBLUE (-475 1075);
FORCEPROP 1 LAST MATERIAL X6S
J 0
(-475 975);
DISPLAY 0.617021 (-475 975);
PAINT SKYBLUE (-475 975);
FORCEPROP 1 LASTPIN (-525 975) $PN 2
J 0
(-515 955);
DISPLAY 0.617021 (-515 955);
PAINT GREEN (-515 955);
FORCEPROP 1 LASTPIN (-525 1175) $PN 1
J 0
(-515 1155);
DISPLAY 0.617021 (-515 1155);
PAINT GREEN (-515 1155);
FORCEPROP 2 LAST BOM_COST PROC_SOCKET
J 0
(-475 1275);
PAINT MONO (-475 1275);
DISPLAY INVISIBLE (-475 1275);
FORCEPROP 2 LAST CDS_LIB mstr_discrete
J 0
(-525 1075);
PAINT ORANGE (-525 1075);
DISPLAY INVISIBLE (-525 1075);
FORCEPROP 2 LAST CDS_SEC 1
J 0
(-475 1275);
DISPLAY 1.361702 (-475 1275);
PAINT ORANGE (-475 1275);
DISPLAY INVISIBLE (-475 1275);
FORCEPROP 2 LAST $SEC 1
J 0
(-475 1275);
DISPLAY 0.914894 (-475 1275);
PAINT MONO (-475 1275);
DISPLAY INVISIBLE (-475 1275);
FORCEPROP 2 LAST CDS_LOCATION C3D3
J 0
(-475 1175);
DISPLAY 0.617021 (-475 1175);
PAINT AQUA (-475 1175);
DISPLAY INVISIBLE (-475 1175);
FORCEPROP 1 LAST PATH I25
J 0
(-475 1225);
DISPLAY 0.978723 (-475 1225);
PAINT WHITE (-475 1225);
DISPLAY INVISIBLE (-475 1225);
FORCEPROP 2 LAST ROOM CPU1
J 0
(-475 1225);
PAINT MONO (-475 1225);
DISPLAY INVISIBLE (-475 1225);
FORCEADD VCC_CORE..1
(-1250 3300);
FORCEPROP 3 LASTPIN (-1250 3250) SIG_NAME PVCCMCP_CPU1\g
J 0
(-1240 3260);
DISPLAY 0.659574 (-1240 3260);
PAINT MONO (-1240 3260);
DISPLAY INVISIBLE (-1240 3260);
FORCEPROP 1 LAST HDL_POWER PVCCMCP_CPU1
J 1
(-1250 3350);
DISPLAY 0.617021 (-1250 3350);
PAINT GREEN (-1250 3350);
FORCEPROP 2 LAST CDS_LIB mstr_symbols
J 0
(-1250 3300);
PAINT ORANGE (-1250 3300);
DISPLAY INVISIBLE (-1250 3300);
FORCEPROP 1 LAST PATH I28
J 0
(-1200 3325);
DISPLAY 0.872340 (-1200 3325);
PAINT AQUA (-1200 3325);
DISPLAY INVISIBLE (-1200 3325);
FORCEADD VCC_CORE..1
(-1250 2575);
FORCEPROP 3 LASTPIN (-1250 2525) SIG_NAME PVCCIOMCP_CPU1\g
J 0
(-1240 2535);
DISPLAY 0.659574 (-1240 2535);
PAINT MONO (-1240 2535);
DISPLAY INVISIBLE (-1240 2535);
FORCEPROP 1 LAST HDL_POWER PVCCIOMCP_CPU1
J 1
(-1250 2625);
DISPLAY 0.617021 (-1250 2625);
PAINT GREEN (-1250 2625);
FORCEPROP 0 LAST VOLTAGE +0.95V
J 0
(-1250 2725);
DISPLAY 1.021277 (-1250 2725);
PAINT SKYBLUE (-1250 2725);
DISPLAY INVISIBLE (-1250 2725);
FORCEPROP 2 LAST CDS_LIB mstr_symbols
J 0
(-1250 2575);
PAINT ORANGE (-1250 2575);
DISPLAY INVISIBLE (-1250 2575);
FORCEPROP 1 LAST PATH I29
J 0
(-1200 2600);
DISPLAY 0.872340 (-1200 2600);
PAINT AQUA (-1200 2600);
DISPLAY INVISIBLE (-1200 2600);
FORCEADD SKX_EXT_B..20
(-6200 2550);
FORCEPROP 1 LAST LOCATION U2D1
J 0
(-7000 4100);
DISPLAY 0.617021 (-7000 4100);
PAINT AQUA (-7000 4100);
FORCEPROP 1 LAST PART_NUMBER TBD
J 0
(-7000 1050);
DISPLAY 0.617021 (-7000 1050);
PAINT BLUE (-7000 1050);
FORCEPROP 1 LAST MATERIAL IC
J 0
(-7000 4050);
DISPLAY 0.617021 (-7000 4050);
PAINT SKYBLUE (-7000 4050);
FORCEPROP 2 LASTPIN (-5350 3850) $PN EE44
J 0
(-5340 3860);
DISPLAY 0.617021 (-5340 3860);
PAINT ORANGE (-5340 3860);
FORCEPROP 2 LASTPIN (-5350 3800) $PN EF45
J 0
(-5340 3810);
DISPLAY 0.617021 (-5340 3810);
PAINT ORANGE (-5340 3810);
FORCEPROP 2 LASTPIN (-5350 3750) $PN DB53
J 0
(-5340 3760);
DISPLAY 0.617021 (-5340 3760);
PAINT ORANGE (-5340 3760);
FORCEPROP 2 LASTPIN (-5350 3700) $PN DB55
J 0
(-5340 3710);
DISPLAY 0.617021 (-5340 3710);
PAINT ORANGE (-5340 3710);
FORCEPROP 2 LASTPIN (-5350 3650) $PN DB57
J 0
(-5340 3660);
DISPLAY 0.617021 (-5340 3660);
PAINT ORANGE (-5340 3660);
FORCEPROP 2 LASTPIN (-5350 3600) $PN DB59
J 0
(-5340 3610);
DISPLAY 0.617021 (-5340 3610);
PAINT ORANGE (-5340 3610);
FORCEPROP 2 LASTPIN (-5350 3550) $PN DB61
J 0
(-5340 3560);
DISPLAY 0.617021 (-5340 3560);
PAINT ORANGE (-5340 3560);
FORCEPROP 2 LASTPIN (-5350 3500) $PN DB63
J 0
(-5340 3510);
DISPLAY 0.617021 (-5340 3510);
PAINT ORANGE (-5340 3510);
FORCEPROP 2 LASTPIN (-5350 3450) $PN DD45
J 0
(-5340 3460);
DISPLAY 0.617021 (-5340 3460);
PAINT ORANGE (-5340 3460);
FORCEPROP 2 LASTPIN (-5350 3400) $PN DH45
J 0
(-5340 3410);
DISPLAY 0.617021 (-5340 3410);
PAINT ORANGE (-5340 3410);
FORCEPROP 2 LASTPIN (-5350 3350) $PN DH47
J 0
(-5340 3360);
DISPLAY 0.617021 (-5340 3360);
PAINT ORANGE (-5340 3360);
FORCEPROP 2 LASTPIN (-5350 3300) $PN DH49
J 0
(-5340 3310);
DISPLAY 0.617021 (-5340 3310);
PAINT ORANGE (-5340 3310);
FORCEPROP 2 LASTPIN (-5350 3250) $PN DH51
J 0
(-5340 3260);
DISPLAY 0.617021 (-5340 3260);
PAINT ORANGE (-5340 3260);
FORCEPROP 2 LASTPIN (-5350 3200) $PN DH53
J 0
(-5340 3210);
DISPLAY 0.617021 (-5340 3210);
PAINT ORANGE (-5340 3210);
FORCEPROP 2 LASTPIN (-5350 3150) $PN DH55
J 0
(-5340 3160);
DISPLAY 0.617021 (-5340 3160);
PAINT ORANGE (-5340 3160);
FORCEPROP 2 LASTPIN (-5350 3100) $PN DH57
J 0
(-5340 3110);
DISPLAY 0.617021 (-5340 3110);
PAINT ORANGE (-5340 3110);
FORCEPROP 2 LASTPIN (-5350 3050) $PN DH59
J 0
(-5340 3060);
DISPLAY 0.617021 (-5340 3060);
PAINT ORANGE (-5340 3060);
FORCEPROP 2 LASTPIN (-5350 3000) $PN DH61
J 0
(-5340 3010);
DISPLAY 0.617021 (-5340 3010);
PAINT ORANGE (-5340 3010);
FORCEPROP 2 LASTPIN (-5350 2950) $PN DH63
J 0
(-5340 2960);
DISPLAY 0.617021 (-5340 2960);
PAINT ORANGE (-5340 2960);
FORCEPROP 2 LASTPIN (-5350 2900) $PN DJ64
J 0
(-5340 2910);
DISPLAY 0.617021 (-5340 2910);
PAINT ORANGE (-5340 2910);
FORCEPROP 2 LASTPIN (-5350 2850) $PN DL46
J 0
(-5340 2860);
DISPLAY 0.617021 (-5340 2860);
PAINT ORANGE (-5340 2860);
FORCEPROP 2 LASTPIN (-5350 2800) $PN DL48
J 0
(-5340 2810);
DISPLAY 0.617021 (-5340 2810);
PAINT ORANGE (-5340 2810);
FORCEPROP 2 LASTPIN (-5350 2750) $PN DL50
J 0
(-5340 2760);
DISPLAY 0.617021 (-5340 2760);
PAINT ORANGE (-5340 2760);
FORCEPROP 2 LASTPIN (-5350 2700) $PN DL52
J 0
(-5340 2710);
DISPLAY 0.617021 (-5340 2710);
PAINT ORANGE (-5340 2710);
FORCEPROP 2 LASTPIN (-5350 2650) $PN DL54
J 0
(-5340 2660);
DISPLAY 0.617021 (-5340 2660);
PAINT ORANGE (-5340 2660);
FORCEPROP 2 LASTPIN (-5350 2600) $PN DL56
J 0
(-5340 2610);
DISPLAY 0.617021 (-5340 2610);
PAINT ORANGE (-5340 2610);
FORCEPROP 2 LASTPIN (-5350 2550) $PN DL58
J 0
(-5340 2560);
DISPLAY 0.617021 (-5340 2560);
PAINT ORANGE (-5340 2560);
FORCEPROP 2 LASTPIN (-5350 2500) $PN DL60
J 0
(-5340 2510);
DISPLAY 0.617021 (-5340 2510);
PAINT ORANGE (-5340 2510);
FORCEPROP 2 LASTPIN (-5350 2450) $PN DL62
J 0
(-5340 2460);
DISPLAY 0.617021 (-5340 2460);
PAINT ORANGE (-5340 2460);
FORCEPROP 2 LASTPIN (-5350 2400) $PN DU46
J 0
(-5340 2410);
DISPLAY 0.617021 (-5340 2410);
PAINT ORANGE (-5340 2410);
FORCEPROP 2 LASTPIN (-5350 2350) $PN DU48
J 0
(-5340 2360);
DISPLAY 0.617021 (-5340 2360);
PAINT ORANGE (-5340 2360);
FORCEPROP 2 LASTPIN (-5350 2300) $PN DU50
J 0
(-5340 2310);
DISPLAY 0.617021 (-5340 2310);
PAINT ORANGE (-5340 2310);
FORCEPROP 2 LASTPIN (-5350 2250) $PN DU52
J 0
(-5340 2260);
DISPLAY 0.617021 (-5340 2260);
PAINT ORANGE (-5340 2260);
FORCEPROP 2 LASTPIN (-5350 2200) $PN DU54
J 0
(-5340 2210);
DISPLAY 0.617021 (-5340 2210);
PAINT ORANGE (-5340 2210);
FORCEPROP 2 LASTPIN (-5350 2150) $PN DU56
J 0
(-5340 2160);
DISPLAY 0.617021 (-5340 2160);
PAINT ORANGE (-5340 2160);
FORCEPROP 2 LASTPIN (-5350 2100) $PN DU58
J 0
(-5340 2110);
DISPLAY 0.617021 (-5340 2110);
PAINT ORANGE (-5340 2110);
FORCEPROP 2 LASTPIN (-5350 2050) $PN DU60
J 0
(-5340 2060);
DISPLAY 0.617021 (-5340 2060);
PAINT ORANGE (-5340 2060);
FORCEPROP 2 LASTPIN (-5350 2000) $PN DU62
J 0
(-5340 2010);
DISPLAY 0.617021 (-5340 2010);
PAINT ORANGE (-5340 2010);
FORCEPROP 2 LASTPIN (-5350 1950) $PN DU64
J 0
(-5340 1960);
DISPLAY 0.617021 (-5340 1960);
PAINT ORANGE (-5340 1960);
FORCEPROP 2 LASTPIN (-5350 1900) $PN EC46
J 0
(-5340 1910);
DISPLAY 0.617021 (-5340 1910);
PAINT ORANGE (-5340 1910);
FORCEPROP 2 LASTPIN (-5350 1850) $PN EC48
J 0
(-5340 1860);
DISPLAY 0.617021 (-5340 1860);
PAINT ORANGE (-5340 1860);
FORCEPROP 2 LASTPIN (-5350 1800) $PN EC50
J 0
(-5340 1810);
DISPLAY 0.617021 (-5340 1810);
PAINT ORANGE (-5340 1810);
FORCEPROP 2 LASTPIN (-5350 1750) $PN EC52
J 0
(-5340 1760);
DISPLAY 0.617021 (-5340 1760);
PAINT ORANGE (-5340 1760);
FORCEPROP 2 LASTPIN (-5350 1700) $PN EC54
J 0
(-5340 1710);
DISPLAY 0.617021 (-5340 1710);
PAINT ORANGE (-5340 1710);
FORCEPROP 2 LASTPIN (-5350 1650) $PN EC56
J 0
(-5340 1660);
DISPLAY 0.617021 (-5340 1660);
PAINT ORANGE (-5340 1660);
FORCEPROP 2 LASTPIN (-5350 1600) $PN EC58
J 0
(-5340 1610);
DISPLAY 0.617021 (-5340 1610);
PAINT ORANGE (-5340 1610);
FORCEPROP 2 LASTPIN (-5350 1550) $PN EC60
J 0
(-5340 1560);
DISPLAY 0.617021 (-5340 1560);
PAINT ORANGE (-5340 1560);
FORCEPROP 2 LASTPIN (-5350 1500) $PN EC62
J 0
(-5340 1510);
DISPLAY 0.617021 (-5340 1510);
PAINT ORANGE (-5340 1510);
FORCEPROP 2 LASTPIN (-5350 1450) $PN EF49
J 0
(-5340 1460);
DISPLAY 0.617021 (-5340 1460);
PAINT ORANGE (-5340 1460);
FORCEPROP 2 LASTPIN (-5350 1350) $PN EF53
J 0
(-5340 1360);
DISPLAY 0.617021 (-5340 1360);
PAINT ORANGE (-5340 1360);
FORCEPROP 2 LASTPIN (-5350 1300) $PN EF59
J 0
(-5340 1310);
DISPLAY 0.617021 (-5340 1310);
PAINT ORANGE (-5340 1310);
FORCEPROP 2 LASTPIN (-7050 3850) $PN B47
J 2
(-7060 3860);
DISPLAY 0.617021 (-7060 3860);
PAINT ORANGE (-7060 3860);
FORCEPROP 2 LASTPIN (-7050 3800) $PN C46
J 2
(-7060 3810);
DISPLAY 0.617021 (-7060 3810);
PAINT ORANGE (-7060 3810);
FORCEPROP 2 LASTPIN (-7050 3750) $PN D45
J 2
(-7060 3760);
DISPLAY 0.617021 (-7060 3760);
PAINT ORANGE (-7060 3760);
FORCEPROP 2 LASTPIN (-7050 3700) $PN AF63
J 2
(-7060 3710);
DISPLAY 0.617021 (-7060 3710);
PAINT ORANGE (-7060 3710);
FORCEPROP 2 LASTPIN (-7050 3650) $PN AF61
J 2
(-7060 3660);
DISPLAY 0.617021 (-7060 3660);
PAINT ORANGE (-7060 3660);
FORCEPROP 2 LASTPIN (-7050 3600) $PN AF59
J 2
(-7060 3610);
DISPLAY 0.617021 (-7060 3610);
PAINT ORANGE (-7060 3610);
FORCEPROP 2 LASTPIN (-7050 3550) $PN AF57
J 2
(-7060 3560);
DISPLAY 0.617021 (-7060 3560);
PAINT ORANGE (-7060 3560);
FORCEPROP 2 LASTPIN (-7050 3500) $PN AF55
J 2
(-7060 3510);
DISPLAY 0.617021 (-7060 3510);
PAINT ORANGE (-7060 3510);
FORCEPROP 2 LASTPIN (-7050 3450) $PN AD45
J 2
(-7060 3460);
DISPLAY 0.617021 (-7060 3460);
PAINT ORANGE (-7060 3460);
FORCEPROP 2 LASTPIN (-7050 3400) $PN Y63
J 2
(-7060 3410);
DISPLAY 0.617021 (-7060 3410);
PAINT ORANGE (-7060 3410);
FORCEPROP 2 LASTPIN (-7050 3350) $PN Y61
J 2
(-7060 3360);
DISPLAY 0.617021 (-7060 3360);
PAINT ORANGE (-7060 3360);
FORCEPROP 2 LASTPIN (-7050 3300) $PN Y59
J 2
(-7060 3310);
DISPLAY 0.617021 (-7060 3310);
PAINT ORANGE (-7060 3310);
FORCEPROP 2 LASTPIN (-7050 3250) $PN Y57
J 2
(-7060 3260);
DISPLAY 0.617021 (-7060 3260);
PAINT ORANGE (-7060 3260);
FORCEPROP 2 LASTPIN (-7050 3200) $PN Y55
J 2
(-7060 3210);
DISPLAY 0.617021 (-7060 3210);
PAINT ORANGE (-7060 3210);
FORCEPROP 2 LASTPIN (-7050 3150) $PN Y53
J 2
(-7060 3160);
DISPLAY 0.617021 (-7060 3160);
PAINT ORANGE (-7060 3160);
FORCEPROP 2 LASTPIN (-7050 3100) $PN Y51
J 2
(-7060 3110);
DISPLAY 0.617021 (-7060 3110);
PAINT ORANGE (-7060 3110);
FORCEPROP 2 LASTPIN (-7050 3050) $PN Y49
J 2
(-7060 3060);
DISPLAY 0.617021 (-7060 3060);
PAINT ORANGE (-7060 3060);
FORCEPROP 2 LASTPIN (-7050 3000) $PN Y47
J 2
(-7060 3010);
DISPLAY 0.617021 (-7060 3010);
PAINT ORANGE (-7060 3010);
FORCEPROP 2 LASTPIN (-7050 2950) $PN Y45
J 2
(-7060 2960);
DISPLAY 0.617021 (-7060 2960);
PAINT ORANGE (-7060 2960);
FORCEPROP 2 LASTPIN (-7050 2900) $PN W64
J 2
(-7060 2910);
DISPLAY 0.617021 (-7060 2910);
PAINT ORANGE (-7060 2910);
FORCEPROP 2 LASTPIN (-7050 2850) $PN U62
J 2
(-7060 2860);
DISPLAY 0.617021 (-7060 2860);
PAINT ORANGE (-7060 2860);
FORCEPROP 2 LASTPIN (-7050 2800) $PN U60
J 2
(-7060 2810);
DISPLAY 0.617021 (-7060 2810);
PAINT ORANGE (-7060 2810);
FORCEPROP 2 LASTPIN (-7050 2750) $PN U58
J 2
(-7060 2760);
DISPLAY 0.617021 (-7060 2760);
PAINT ORANGE (-7060 2760);
FORCEPROP 2 LASTPIN (-7050 2700) $PN U56
J 2
(-7060 2710);
DISPLAY 0.617021 (-7060 2710);
PAINT ORANGE (-7060 2710);
FORCEPROP 2 LASTPIN (-7050 2650) $PN U54
J 2
(-7060 2660);
DISPLAY 0.617021 (-7060 2660);
PAINT ORANGE (-7060 2660);
FORCEPROP 2 LASTPIN (-7050 2600) $PN U52
J 2
(-7060 2610);
DISPLAY 0.617021 (-7060 2610);
PAINT ORANGE (-7060 2610);
FORCEPROP 2 LASTPIN (-7050 2550) $PN U50
J 2
(-7060 2560);
DISPLAY 0.617021 (-7060 2560);
PAINT ORANGE (-7060 2560);
FORCEPROP 2 LASTPIN (-7050 2500) $PN U48
J 2
(-7060 2510);
DISPLAY 0.617021 (-7060 2510);
PAINT ORANGE (-7060 2510);
FORCEPROP 2 LASTPIN (-7050 2450) $PN U46
J 2
(-7060 2460);
DISPLAY 0.617021 (-7060 2460);
PAINT ORANGE (-7060 2460);
FORCEPROP 2 LASTPIN (-7050 2400) $PN N64
J 2
(-7060 2410);
DISPLAY 0.617021 (-7060 2410);
PAINT ORANGE (-7060 2410);
FORCEPROP 2 LASTPIN (-7050 2350) $PN L62
J 2
(-7060 2360);
DISPLAY 0.617021 (-7060 2360);
PAINT ORANGE (-7060 2360);
FORCEPROP 2 LASTPIN (-7050 2300) $PN L60
J 2
(-7060 2310);
DISPLAY 0.617021 (-7060 2310);
PAINT ORANGE (-7060 2310);
FORCEPROP 2 LASTPIN (-7050 2250) $PN L58
J 2
(-7060 2260);
DISPLAY 0.617021 (-7060 2260);
PAINT ORANGE (-7060 2260);
FORCEPROP 2 LASTPIN (-7050 2200) $PN L56
J 2
(-7060 2210);
DISPLAY 0.617021 (-7060 2210);
PAINT ORANGE (-7060 2210);
FORCEPROP 2 LASTPIN (-7050 2150) $PN L54
J 2
(-7060 2160);
DISPLAY 0.617021 (-7060 2160);
PAINT ORANGE (-7060 2160);
FORCEPROP 2 LASTPIN (-7050 2100) $PN L52
J 2
(-7060 2110);
DISPLAY 0.617021 (-7060 2110);
PAINT ORANGE (-7060 2110);
FORCEPROP 2 LASTPIN (-7050 2050) $PN L50
J 2
(-7060 2060);
DISPLAY 0.617021 (-7060 2060);
PAINT ORANGE (-7060 2060);
FORCEPROP 2 LASTPIN (-7050 2000) $PN L48
J 2
(-7060 2010);
DISPLAY 0.617021 (-7060 2010);
PAINT ORANGE (-7060 2010);
FORCEPROP 2 LASTPIN (-7050 1950) $PN L46
J 2
(-7060 1960);
DISPLAY 0.617021 (-7060 1960);
PAINT ORANGE (-7060 1960);
FORCEPROP 2 LASTPIN (-7050 1900) $PN E64
J 2
(-7060 1910);
DISPLAY 0.617021 (-7060 1910);
PAINT ORANGE (-7060 1910);
FORCEPROP 2 LASTPIN (-7050 1850) $PN E62
J 2
(-7060 1860);
DISPLAY 0.617021 (-7060 1860);
PAINT ORANGE (-7060 1860);
FORCEPROP 2 LASTPIN (-7050 1800) $PN E60
J 2
(-7060 1810);
DISPLAY 0.617021 (-7060 1810);
PAINT ORANGE (-7060 1810);
FORCEPROP 2 LASTPIN (-7050 1750) $PN E58
J 2
(-7060 1760);
DISPLAY 0.617021 (-7060 1760);
PAINT ORANGE (-7060 1760);
FORCEPROP 2 LASTPIN (-7050 1700) $PN E56
J 2
(-7060 1710);
DISPLAY 0.617021 (-7060 1710);
PAINT ORANGE (-7060 1710);
FORCEPROP 2 LASTPIN (-7050 1650) $PN E54
J 2
(-7060 1660);
DISPLAY 0.617021 (-7060 1660);
PAINT ORANGE (-7060 1660);
FORCEPROP 2 LASTPIN (-7050 1600) $PN E52
J 2
(-7060 1610);
DISPLAY 0.617021 (-7060 1610);
PAINT ORANGE (-7060 1610);
FORCEPROP 2 LASTPIN (-7050 1550) $PN E50
J 2
(-7060 1560);
DISPLAY 0.617021 (-7060 1560);
PAINT ORANGE (-7060 1560);
FORCEPROP 2 LASTPIN (-7050 1500) $PN E48
J 2
(-7060 1510);
DISPLAY 0.617021 (-7060 1510);
PAINT ORANGE (-7060 1510);
FORCEPROP 2 LASTPIN (-7050 1450) $PN E46
J 2
(-7060 1460);
DISPLAY 0.617021 (-7060 1460);
PAINT ORANGE (-7060 1460);
FORCEPROP 2 LASTPIN (-7050 1350) $PN B59
J 2
(-7060 1360);
DISPLAY 0.617021 (-7060 1360);
PAINT ORANGE (-7060 1360);
FORCEPROP 2 LASTPIN (-7050 1300) $PN B53
J 2
(-7060 1310);
DISPLAY 0.617021 (-7060 1310);
PAINT ORANGE (-7060 1310);
FORCEPROP 2 LASTPIN (-7050 1250) $PN B49
J 2
(-7060 1260);
DISPLAY 0.617021 (-7060 1260);
PAINT ORANGE (-7060 1260);
FORCEPROP 1 LAST PACK_TYPE BGA1
J 0
(-7000 4150);
PAINT SKYBLUE (-7000 4150);
DISPLAY INVISIBLE (-7000 4150);
FORCEPROP 2 LAST SEC_TYPE BGA1
J 0
(-7000 4150);
DISPLAY 1.021277 (-7000 4150);
PAINT ORANGE (-7000 4150);
DISPLAY INVISIBLE (-7000 4150);
FORCEPROP 2 LAST CDS_LIB chpset_lib
J 0
(-6200 2550);
PAINT ORANGE (-6200 2550);
DISPLAY INVISIBLE (-6200 2550);
FORCEPROP 2 LAST SEC 20
J 0
(-7000 4150);
DISPLAY 0.680851 (-7000 4150);
PAINT MONO (-7000 4150);
DISPLAY INVISIBLE (-7000 4150);
FORCEPROP 2 LAST CDS_LOCATION U2D1
J 0
(-7000 4100);
DISPLAY 0.617021 (-7000 4100);
PAINT AQUA (-7000 4100);
DISPLAY INVISIBLE (-7000 4100);
FORCEPROP 1 LAST PATH I32
J 0
(-6200 4050);
PAINT GREEN (-6200 4050);
DISPLAY INVISIBLE (-6200 4050);
FORCEADD SKX_EXT_B..21
(-2700 2575);
FORCEPROP 1 LAST LOCATION U2D1
J 0
(-3550 4825);
DISPLAY 0.617021 (-3550 4825);
PAINT AQUA (-3550 4825);
FORCEPROP 1 LAST PART_NUMBER TBD
J 0
(-3550 325);
DISPLAY 0.617021 (-3550 325);
PAINT BLUE (-3550 325);
FORCEPROP 1 LAST MATERIAL IC
J 0
(-3550 4775);
DISPLAY 0.617021 (-3550 4775);
PAINT SKYBLUE (-3550 4775);
FORCEPROP 2 LASTPIN (-1800 4575) $PN CB65
J 0
(-1790 4585);
DISPLAY 0.617021 (-1790 4585);
PAINT ORANGE (-1790 4585);
FORCEPROP 2 LASTPIN (-1800 4525) $PN CB67
J 0
(-1790 4535);
DISPLAY 0.617021 (-1790 4535);
PAINT ORANGE (-1790 4535);
FORCEPROP 2 LASTPIN (-1800 4475) $PN CB69
J 0
(-1790 4485);
DISPLAY 0.617021 (-1790 4485);
PAINT ORANGE (-1790 4485);
FORCEPROP 2 LASTPIN (-1800 4425) $PN CC66
J 0
(-1790 4435);
DISPLAY 0.617021 (-1790 4435);
PAINT ORANGE (-1790 4435);
FORCEPROP 2 LASTPIN (-1800 4375) $PN CC68
J 0
(-1790 4385);
DISPLAY 0.617021 (-1790 4385);
PAINT ORANGE (-1790 4385);
FORCEPROP 2 LASTPIN (-1800 4325) $PN CC70
J 0
(-1790 4335);
DISPLAY 0.617021 (-1790 4335);
PAINT ORANGE (-1790 4335);
FORCEPROP 2 LASTPIN (-1800 4275) $PN CD65
J 0
(-1790 4285);
DISPLAY 0.617021 (-1790 4285);
PAINT ORANGE (-1790 4285);
FORCEPROP 2 LASTPIN (-1800 4225) $PN CD67
J 0
(-1790 4235);
DISPLAY 0.617021 (-1790 4235);
PAINT ORANGE (-1790 4235);
FORCEPROP 2 LASTPIN (-1800 4175) $PN CD69
J 0
(-1790 4185);
DISPLAY 0.617021 (-1790 4185);
PAINT ORANGE (-1790 4185);
FORCEPROP 2 LASTPIN (-1800 4125) $PN CD71
J 0
(-1790 4135);
DISPLAY 0.617021 (-1790 4135);
PAINT ORANGE (-1790 4135);
FORCEPROP 2 LASTPIN (-1800 4075) $PN CE64
J 0
(-1790 4085);
DISPLAY 0.617021 (-1790 4085);
PAINT ORANGE (-1790 4085);
FORCEPROP 2 LASTPIN (-1800 4025) $PN CE66
J 0
(-1790 4035);
DISPLAY 0.617021 (-1790 4035);
PAINT ORANGE (-1790 4035);
FORCEPROP 2 LASTPIN (-1800 3975) $PN CE68
J 0
(-1790 3985);
DISPLAY 0.617021 (-1790 3985);
PAINT ORANGE (-1790 3985);
FORCEPROP 2 LASTPIN (-1800 3925) $PN CE72
J 0
(-1790 3935);
DISPLAY 0.617021 (-1790 3935);
PAINT ORANGE (-1790 3935);
FORCEPROP 2 LASTPIN (-1800 3875) $PN CE74
J 0
(-1790 3885);
DISPLAY 0.617021 (-1790 3885);
PAINT ORANGE (-1790 3885);
FORCEPROP 2 LASTPIN (-1800 3825) $PN CF65
J 0
(-1790 3835);
DISPLAY 0.617021 (-1790 3835);
PAINT ORANGE (-1790 3835);
FORCEPROP 2 LASTPIN (-1800 3775) $PN CF67
J 0
(-1790 3785);
DISPLAY 0.617021 (-1790 3785);
PAINT ORANGE (-1790 3785);
FORCEPROP 2 LASTPIN (-1800 3725) $PN CF73
J 0
(-1790 3735);
DISPLAY 0.617021 (-1790 3735);
PAINT ORANGE (-1790 3735);
FORCEPROP 2 LASTPIN (-1800 3675) $PN CF75
J 0
(-1790 3685);
DISPLAY 0.617021 (-1790 3685);
PAINT ORANGE (-1790 3685);
FORCEPROP 2 LASTPIN (-1800 3625) $PN CG64
J 0
(-1790 3635);
DISPLAY 0.617021 (-1790 3635);
PAINT ORANGE (-1790 3635);
FORCEPROP 2 LASTPIN (-1800 3575) $PN CG66
J 0
(-1790 3585);
DISPLAY 0.617021 (-1790 3585);
PAINT ORANGE (-1790 3585);
FORCEPROP 2 LASTPIN (-1800 3525) $PN CG74
J 0
(-1790 3535);
DISPLAY 0.617021 (-1790 3535);
PAINT ORANGE (-1790 3535);
FORCEPROP 2 LASTPIN (-1800 3475) $PN CH65
J 0
(-1790 3485);
DISPLAY 0.617021 (-1790 3485);
PAINT ORANGE (-1790 3485);
FORCEPROP 2 LASTPIN (-1800 3425) $PN CH75
J 0
(-1790 3435);
DISPLAY 0.617021 (-1790 3435);
PAINT ORANGE (-1790 3435);
FORCEPROP 2 LASTPIN (-1800 3375) $PN CJ64
J 0
(-1790 3385);
DISPLAY 0.617021 (-1790 3385);
PAINT ORANGE (-1790 3385);
FORCEPROP 2 LASTPIN (-1800 3325) $PN CJ66
J 0
(-1790 3335);
DISPLAY 0.617021 (-1790 3335);
PAINT ORANGE (-1790 3335);
FORCEPROP 2 LASTPIN (-3600 4575) $PN AR28
J 2
(-3610 4585);
DISPLAY 0.617021 (-3610 4585);
PAINT ORANGE (-3610 4585);
FORCEPROP 2 LASTPIN (-3600 4525) $PN AL28
J 2
(-3610 4535);
DISPLAY 0.617021 (-3610 4535);
PAINT ORANGE (-3610 4535);
FORCEPROP 2 LASTPIN (-3600 4475) $PN AM29
J 2
(-3610 4485);
DISPLAY 0.617021 (-3610 4485);
PAINT ORANGE (-3610 4485);
FORCEPROP 2 LASTPIN (-3600 4425) $PN AG34
J 2
(-3610 4435);
DISPLAY 0.617021 (-3610 4435);
PAINT ORANGE (-3610 4435);
FORCEPROP 2 LASTPIN (-3600 4375) $PN AE34
J 2
(-3610 4385);
DISPLAY 0.617021 (-3610 4385);
PAINT ORANGE (-3610 4385);
FORCEPROP 2 LASTPIN (-3600 4325) $PN AD35
J 2
(-3610 4335);
DISPLAY 0.617021 (-3610 4335);
PAINT ORANGE (-3610 4335);
FORCEPROP 2 LASTPIN (-3600 4275) $PN AF35
J 2
(-3610 4285);
DISPLAY 0.617021 (-3610 4285);
PAINT ORANGE (-3610 4285);
FORCEPROP 2 LASTPIN (-3600 4225) $PN AC36
J 2
(-3610 4235);
DISPLAY 0.617021 (-3610 4235);
PAINT ORANGE (-3610 4235);
FORCEPROP 2 LASTPIN (-3600 4175) $PN AD37
J 2
(-3610 4185);
DISPLAY 0.617021 (-3610 4185);
PAINT ORANGE (-3610 4185);
FORCEPROP 2 LASTPIN (-3600 4125) $PN AE36
J 2
(-3610 4135);
DISPLAY 0.617021 (-3610 4135);
PAINT ORANGE (-3610 4135);
FORCEPROP 2 LASTPIN (-3600 4075) $PN BF27
J 2
(-3610 4085);
DISPLAY 0.617021 (-3610 4085);
PAINT ORANGE (-3610 4085);
FORCEPROP 2 LASTPIN (-3600 4025) $PN BG26
J 2
(-3610 4035);
DISPLAY 0.617021 (-3610 4035);
PAINT ORANGE (-3610 4035);
FORCEPROP 2 LASTPIN (-3600 3975) $PN BH25
J 2
(-3610 3985);
DISPLAY 0.617021 (-3610 3985);
PAINT ORANGE (-3610 3985);
FORCEPROP 2 LASTPIN (-3600 3925) $PN BH27
J 2
(-3610 3935);
DISPLAY 0.617021 (-3610 3935);
PAINT ORANGE (-3610 3935);
FORCEPROP 2 LASTPIN (-3600 3875) $PN BJ26
J 2
(-3610 3885);
DISPLAY 0.617021 (-3610 3885);
PAINT ORANGE (-3610 3885);
FORCEPROP 2 LASTPIN (-3600 3825) $PN BK25
J 2
(-3610 3835);
DISPLAY 0.617021 (-3610 3835);
PAINT ORANGE (-3610 3835);
FORCEPROP 2 LASTPIN (-3600 3775) $PN BK27
J 2
(-3610 3785);
DISPLAY 0.617021 (-3610 3785);
PAINT ORANGE (-3610 3785);
FORCEPROP 2 LASTPIN (-3600 3725) $PN BL26
J 2
(-3610 3735);
DISPLAY 0.617021 (-3610 3735);
PAINT ORANGE (-3610 3735);
FORCEPROP 2 LASTPIN (-3600 3675) $PN BM27
J 2
(-3610 3685);
DISPLAY 0.617021 (-3610 3685);
PAINT ORANGE (-3610 3685);
FORCEPROP 2 LASTPIN (-3600 3625) $PN CH27
J 2
(-3610 3635);
DISPLAY 0.617021 (-3610 3635);
PAINT ORANGE (-3610 3635);
FORCEPROP 2 LASTPIN (-3600 3575) $PN CJ28
J 2
(-3610 3585);
DISPLAY 0.617021 (-3610 3585);
PAINT ORANGE (-3610 3585);
FORCEPROP 2 LASTPIN (-3600 3525) $PN CC26
J 2
(-3610 3535);
DISPLAY 0.617021 (-3610 3535);
PAINT ORANGE (-3610 3535);
FORCEPROP 2 LASTPIN (-3600 3475) $PN CD27
J 2
(-3610 3485);
DISPLAY 0.617021 (-3610 3485);
PAINT ORANGE (-3610 3485);
FORCEPROP 2 LASTPIN (-3600 3425) $PN CF27
J 2
(-3610 3435);
DISPLAY 0.617021 (-3610 3435);
PAINT ORANGE (-3610 3435);
FORCEPROP 2 LASTPIN (-3600 3375) $PN AV27
J 2
(-3610 3385);
DISPLAY 0.617021 (-3610 3385);
PAINT ORANGE (-3610 3385);
FORCEPROP 2 LASTPIN (-3600 3325) $PN AW26
J 2
(-3610 3335);
DISPLAY 0.617021 (-3610 3335);
PAINT ORANGE (-3610 3335);
FORCEPROP 2 LASTPIN (-3600 3275) $PN AY27
J 2
(-3610 3285);
DISPLAY 0.617021 (-3610 3285);
PAINT ORANGE (-3610 3285);
FORCEPROP 2 LASTPIN (-3600 3225) $PN BA26
J 2
(-3610 3235);
DISPLAY 0.617021 (-3610 3235);
PAINT ORANGE (-3610 3235);
FORCEPROP 2 LASTPIN (-3600 3175) $PN BB27
J 2
(-3610 3185);
DISPLAY 0.617021 (-3610 3185);
PAINT ORANGE (-3610 3185);
FORCEPROP 2 LASTPIN (-3600 3125) $PN BC26
J 2
(-3610 3135);
DISPLAY 0.617021 (-3610 3135);
PAINT ORANGE (-3610 3135);
FORCEPROP 2 LASTPIN (-3600 3075) $PN W10
J 2
(-3610 3085);
DISPLAY 0.617021 (-3610 3085);
PAINT ORANGE (-3610 3085);
FORCEPROP 2 LASTPIN (-3600 3025) $PN N18
J 2
(-3610 3035);
DISPLAY 0.617021 (-3610 3035);
PAINT ORANGE (-3610 3035);
FORCEPROP 2 LASTPIN (-3600 2975) $PN M9
J 2
(-3610 2985);
DISPLAY 0.617021 (-3610 2985);
PAINT ORANGE (-3610 2985);
FORCEPROP 2 LASTPIN (-3600 2925) $PN M7
J 2
(-3610 2935);
DISPLAY 0.617021 (-3610 2935);
PAINT ORANGE (-3610 2935);
FORCEPROP 2 LASTPIN (-3600 2875) $PN K15
J 2
(-3610 2885);
DISPLAY 0.617021 (-3610 2885);
PAINT ORANGE (-3610 2885);
FORCEPROP 2 LASTPIN (-3600 2825) $PN J2
J 2
(-3610 2835);
DISPLAY 0.617021 (-3610 2835);
PAINT ORANGE (-3610 2835);
FORCEPROP 2 LASTPIN (-3600 2775) $PN EB15
J 2
(-3610 2785);
DISPLAY 0.617021 (-3610 2785);
PAINT ORANGE (-3610 2785);
FORCEPROP 2 LASTPIN (-3600 2725) $PN EA12
J 2
(-3610 2735);
DISPLAY 0.617021 (-3610 2735);
PAINT ORANGE (-3610 2735);
FORCEPROP 2 LASTPIN (-3600 2675) $PN DU20
J 2
(-3610 2685);
DISPLAY 0.617021 (-3610 2685);
PAINT ORANGE (-3610 2685);
FORCEPROP 2 LASTPIN (-3600 2625) $PN DR2
J 2
(-3610 2635);
DISPLAY 0.617021 (-3610 2635);
PAINT ORANGE (-3610 2635);
FORCEPROP 2 LASTPIN (-3600 2575) $PN DR10
J 2
(-3610 2585);
DISPLAY 0.617021 (-3610 2585);
PAINT ORANGE (-3610 2585);
FORCEPROP 2 LASTPIN (-3600 2525) $PN DP19
J 2
(-3610 2535);
DISPLAY 0.617021 (-3610 2535);
PAINT ORANGE (-3610 2535);
FORCEPROP 2 LASTPIN (-3600 2475) $PN DN8
J 2
(-3610 2485);
DISPLAY 0.617021 (-3610 2485);
PAINT ORANGE (-3610 2485);
FORCEPROP 2 LASTPIN (-3600 2425) $PN DM17
J 2
(-3610 2435);
DISPLAY 0.617021 (-3610 2435);
PAINT ORANGE (-3610 2435);
FORCEPROP 2 LASTPIN (-3600 2375) $PN DJ16
J 2
(-3610 2385);
DISPLAY 0.617021 (-3610 2385);
PAINT ORANGE (-3610 2385);
FORCEPROP 2 LASTPIN (-3600 2325) $PN H13
J 2
(-3610 2335);
DISPLAY 0.617021 (-3610 2335);
PAINT ORANGE (-3610 2335);
FORCEPROP 2 LASTPIN (-3600 2275) $PN J10
J 2
(-3610 2285);
DISPLAY 0.617021 (-3610 2285);
PAINT ORANGE (-3610 2285);
FORCEPROP 2 LASTPIN (-3600 2225) $PN L14
J 2
(-3610 2235);
DISPLAY 0.617021 (-3610 2235);
PAINT ORANGE (-3610 2235);
FORCEPROP 2 LASTPIN (-3600 2175) $PN L16
J 2
(-3610 2185);
DISPLAY 0.617021 (-3610 2185);
PAINT ORANGE (-3610 2185);
FORCEPROP 2 LASTPIN (-3600 2125) $PN DH7
J 2
(-3610 2135);
DISPLAY 0.617021 (-3610 2135);
PAINT ORANGE (-3610 2135);
FORCEPROP 2 LASTPIN (-3600 2075) $PN DG8
J 2
(-3610 2085);
DISPLAY 0.617021 (-3610 2085);
PAINT ORANGE (-3610 2085);
FORCEPROP 2 LASTPIN (-3600 2025) $PN M11
J 2
(-3610 2035);
DISPLAY 0.617021 (-3610 2035);
PAINT ORANGE (-3610 2035);
FORCEPROP 2 LASTPIN (-3600 1975) $PN M21
J 2
(-3610 1985);
DISPLAY 0.617021 (-3610 1985);
PAINT ORANGE (-3610 1985);
FORCEPROP 2 LASTPIN (-3600 1925) $PN P5
J 2
(-3610 1935);
DISPLAY 0.617021 (-3610 1935);
PAINT ORANGE (-3610 1935);
FORCEPROP 2 LASTPIN (-3600 1875) $PN T3
J 2
(-3610 1885);
DISPLAY 0.617021 (-3610 1885);
PAINT ORANGE (-3610 1885);
FORCEPROP 2 LASTPIN (-3600 1825) $PN U14
J 2
(-3610 1835);
DISPLAY 0.617021 (-3610 1835);
PAINT ORANGE (-3610 1835);
FORCEPROP 2 LASTPIN (-3600 1775) $PN DF21
J 2
(-3610 1785);
DISPLAY 0.617021 (-3610 1785);
PAINT ORANGE (-3610 1785);
FORCEPROP 2 LASTPIN (-3600 1725) $PN W4
J 2
(-3610 1735);
DISPLAY 0.617021 (-3610 1735);
PAINT ORANGE (-3610 1735);
FORCEPROP 2 LASTPIN (-3600 1675) $PN W6
J 2
(-3610 1685);
DISPLAY 0.617021 (-3610 1685);
PAINT ORANGE (-3610 1685);
FORCEPROP 2 LASTPIN (-3600 1625) $PN AA10
J 2
(-3610 1635);
DISPLAY 0.617021 (-3610 1635);
PAINT ORANGE (-3610 1635);
FORCEPROP 2 LASTPIN (-3600 1575) $PN AC20
J 2
(-3610 1585);
DISPLAY 0.617021 (-3610 1585);
PAINT ORANGE (-3610 1585);
FORCEPROP 2 LASTPIN (-3600 1525) $PN AC4
J 2
(-3610 1535);
DISPLAY 0.617021 (-3610 1535);
PAINT ORANGE (-3610 1535);
FORCEPROP 2 LASTPIN (-3600 1475) $PN AH9
J 2
(-3610 1485);
DISPLAY 0.617021 (-3610 1485);
PAINT ORANGE (-3610 1485);
FORCEPROP 2 LASTPIN (-3600 1425) $PN DF13
J 2
(-3610 1435);
DISPLAY 0.617021 (-3610 1435);
PAINT ORANGE (-3610 1435);
FORCEPROP 2 LASTPIN (-3600 1375) $PN AN10
J 2
(-3610 1385);
DISPLAY 0.617021 (-3610 1385);
PAINT ORANGE (-3610 1385);
FORCEPROP 2 LASTPIN (-3600 1325) $PN DD7
J 2
(-3610 1335);
DISPLAY 0.617021 (-3610 1335);
PAINT ORANGE (-3610 1335);
FORCEPROP 2 LASTPIN (-3600 1275) $PN AT11
J 2
(-3610 1285);
DISPLAY 0.617021 (-3610 1285);
PAINT ORANGE (-3610 1285);
FORCEPROP 2 LASTPIN (-3600 1225) $PN AW6
J 2
(-3610 1235);
DISPLAY 0.617021 (-3610 1235);
PAINT ORANGE (-3610 1235);
FORCEPROP 2 LASTPIN (-3600 1175) $PN AY11
J 2
(-3610 1185);
DISPLAY 0.617021 (-3610 1185);
PAINT ORANGE (-3610 1185);
FORCEPROP 2 LASTPIN (-3600 1125) $PN BA24
J 2
(-3610 1135);
DISPLAY 0.617021 (-3610 1135);
PAINT ORANGE (-3610 1135);
FORCEPROP 2 LASTPIN (-3600 1075) $PN BB5
J 2
(-3610 1085);
DISPLAY 0.617021 (-3610 1085);
PAINT ORANGE (-3610 1085);
FORCEPROP 2 LASTPIN (-3600 1025) $PN DA14
J 2
(-3610 1035);
DISPLAY 0.617021 (-3610 1035);
PAINT ORANGE (-3610 1035);
FORCEPROP 2 LASTPIN (-3600 975) $PN BF23
J 2
(-3610 985);
DISPLAY 0.617021 (-3610 985);
PAINT ORANGE (-3610 985);
FORCEPROP 2 LASTPIN (-3600 925) $PN BJ24
J 2
(-3610 935);
DISPLAY 0.617021 (-3610 935);
PAINT ORANGE (-3610 935);
FORCEPROP 2 LASTPIN (-3600 875) $PN BP25
J 2
(-3610 885);
DISPLAY 0.617021 (-3610 885);
PAINT ORANGE (-3610 885);
FORCEPROP 2 LASTPIN (-1800 1025) $PN CB13
J 0
(-1790 1035);
DISPLAY 0.617021 (-1790 1035);
PAINT ORANGE (-1790 1035);
FORCEPROP 2 LASTPIN (-1800 975) $PN CB17
J 0
(-1790 985);
DISPLAY 0.617021 (-1790 985);
PAINT ORANGE (-1790 985);
FORCEPROP 2 LASTPIN (-1800 925) $PN CD9
J 0
(-1790 935);
DISPLAY 0.617021 (-1790 935);
PAINT ORANGE (-1790 935);
FORCEPROP 2 LASTPIN (-1800 875) $PN CE18
J 0
(-1790 885);
DISPLAY 0.617021 (-1790 885);
PAINT ORANGE (-1790 885);
FORCEPROP 2 LASTPIN (-1800 825) $PN D7
J 0
(-1790 835);
DISPLAY 0.617021 (-1790 835);
PAINT ORANGE (-1790 835);
FORCEPROP 2 LASTPIN (-1800 775) $PN CH9
J 0
(-1790 785);
DISPLAY 0.617021 (-1790 785);
PAINT ORANGE (-1790 785);
FORCEPROP 2 LASTPIN (-1800 675) $PN CV7
J 0
(-1790 685);
DISPLAY 0.617021 (-1790 685);
PAINT ORANGE (-1790 685);
FORCEPROP 2 LASTPIN (-1800 625) $PN CK5
J 0
(-1790 635);
DISPLAY 0.617021 (-1790 635);
PAINT ORANGE (-1790 635);
FORCEPROP 2 LASTPIN (-1800 575) $PN CL12
J 0
(-1790 585);
DISPLAY 0.617021 (-1790 585);
PAINT ORANGE (-1790 585);
FORCEPROP 2 LASTPIN (-1800 525) $PN CM15
J 0
(-1790 535);
DISPLAY 0.617021 (-1790 535);
PAINT ORANGE (-1790 535);
FORCEPROP 2 LASTPIN (-1800 1125) $PN CY55
J 0
(-1790 1135);
DISPLAY 0.617021 (-1790 1135);
PAINT ORANGE (-1790 1135);
FORCEPROP 2 LASTPIN (-1800 1625) $PN A8
J 0
(-1790 1635);
DISPLAY 0.617021 (-1790 1635);
PAINT ORANGE (-1790 1635);
FORCEPROP 2 LASTPIN (-1800 1575) $PN A10
J 0
(-1790 1585);
DISPLAY 0.617021 (-1790 1585);
PAINT ORANGE (-1790 1585);
FORCEPROP 2 LASTPIN (-1800 1525) $PN A12
J 0
(-1790 1535);
DISPLAY 0.617021 (-1790 1535);
PAINT ORANGE (-1790 1535);
FORCEPROP 2 LASTPIN (-1800 1475) $PN B11
J 0
(-1790 1485);
DISPLAY 0.617021 (-1790 1485);
PAINT ORANGE (-1790 1485);
FORCEPROP 2 LASTPIN (-1800 2525) $PN BM11
J 0
(-1790 2535);
DISPLAY 0.617021 (-1790 2535);
PAINT ORANGE (-1790 2535);
FORCEPROP 2 LASTPIN (-1800 2475) $PN BN12
J 0
(-1790 2485);
DISPLAY 0.617021 (-1790 2485);
PAINT ORANGE (-1790 2485);
FORCEPROP 2 LASTPIN (-1800 2425) $PN BN14
J 0
(-1790 2435);
DISPLAY 0.617021 (-1790 2435);
PAINT ORANGE (-1790 2435);
FORCEPROP 2 LASTPIN (-1800 2375) $PN BP11
J 0
(-1790 2385);
DISPLAY 0.617021 (-1790 2385);
PAINT ORANGE (-1790 2385);
FORCEPROP 2 LASTPIN (-1800 2325) $PN BP13
J 0
(-1790 2335);
DISPLAY 0.617021 (-1790 2335);
PAINT ORANGE (-1790 2335);
FORCEPROP 2 LASTPIN (-1800 2275) $PN BP15
J 0
(-1790 2285);
DISPLAY 0.617021 (-1790 2285);
PAINT ORANGE (-1790 2285);
FORCEPROP 2 LASTPIN (-1800 2175) $PN BR12
J 0
(-1790 2185);
DISPLAY 0.617021 (-1790 2185);
PAINT ORANGE (-1790 2185);
FORCEPROP 2 LASTPIN (-1800 2125) $PN BR14
J 0
(-1790 2135);
DISPLAY 0.617021 (-1790 2135);
PAINT ORANGE (-1790 2135);
FORCEPROP 2 LASTPIN (-1800 2075) $PN BT11
J 0
(-1790 2085);
DISPLAY 0.617021 (-1790 2085);
PAINT ORANGE (-1790 2085);
FORCEPROP 2 LASTPIN (-1800 2025) $PN BT13
J 0
(-1790 2035);
DISPLAY 0.617021 (-1790 2035);
PAINT ORANGE (-1790 2035);
FORCEPROP 2 LASTPIN (-1800 1975) $PN BT15
J 0
(-1790 1985);
DISPLAY 0.617021 (-1790 1985);
PAINT ORANGE (-1790 1985);
FORCEPROP 2 LASTPIN (-1800 1925) $PN BU12
J 0
(-1790 1935);
DISPLAY 0.617021 (-1790 1935);
PAINT ORANGE (-1790 1935);
FORCEPROP 2 LASTPIN (-1800 1875) $PN BU14
J 0
(-1790 1885);
DISPLAY 0.617021 (-1790 1885);
PAINT ORANGE (-1790 1885);
FORCEPROP 2 LASTPIN (-1800 1825) $PN BV11
J 0
(-1790 1835);
DISPLAY 0.617021 (-1790 1835);
PAINT ORANGE (-1790 1835);
FORCEPROP 2 LASTPIN (-1800 1775) $PN BV13
J 0
(-1790 1785);
DISPLAY 0.617021 (-1790 1785);
PAINT ORANGE (-1790 1785);
FORCEPROP 2 LASTPIN (-1800 1725) $PN BV15
J 0
(-1790 1735);
DISPLAY 0.617021 (-1790 1735);
PAINT ORANGE (-1790 1735);
FORCEPROP 2 LASTPIN (-1800 1375) $PN BY27
J 0
(-1790 1385);
DISPLAY 0.617021 (-1790 1385);
PAINT ORANGE (-1790 1385);
FORCEPROP 2 LASTPIN (-1800 1325) $PN BV27
J 0
(-1790 1335);
DISPLAY 0.617021 (-1790 1335);
PAINT ORANGE (-1790 1335);
FORCEPROP 2 LASTPIN (-1800 1275) $PN BU26
J 0
(-1790 1285);
DISPLAY 0.617021 (-1790 1285);
PAINT ORANGE (-1790 1285);
FORCEPROP 2 LASTPIN (-1800 1225) $PN BT27
J 0
(-1790 1235);
DISPLAY 0.617021 (-1790 1235);
PAINT ORANGE (-1790 1235);
FORCEPROP 2 LASTPIN (-1800 3225) $PN BD13
J 0
(-1790 3235);
DISPLAY 0.617021 (-1790 3235);
PAINT ORANGE (-1790 3235);
FORCEPROP 2 LASTPIN (-1800 3175) $PN BE12
J 0
(-1790 3185);
DISPLAY 0.617021 (-1790 3185);
PAINT ORANGE (-1790 3185);
FORCEPROP 2 LASTPIN (-1800 3125) $PN BE14
J 0
(-1790 3135);
DISPLAY 0.617021 (-1790 3135);
PAINT ORANGE (-1790 3135);
FORCEPROP 2 LASTPIN (-1800 3075) $PN BF11
J 0
(-1790 3085);
DISPLAY 0.617021 (-1790 3085);
PAINT ORANGE (-1790 3085);
FORCEPROP 2 LASTPIN (-1800 3025) $PN BF13
J 0
(-1790 3035);
DISPLAY 0.617021 (-1790 3035);
PAINT ORANGE (-1790 3035);
FORCEPROP 2 LASTPIN (-1800 2975) $PN BG12
J 0
(-1790 2985);
DISPLAY 0.617021 (-1790 2985);
PAINT ORANGE (-1790 2985);
FORCEPROP 2 LASTPIN (-1800 2925) $PN BG14
J 0
(-1790 2935);
DISPLAY 0.617021 (-1790 2935);
PAINT ORANGE (-1790 2935);
FORCEPROP 2 LASTPIN (-1800 2875) $PN BH13
J 0
(-1790 2885);
DISPLAY 0.617021 (-1790 2885);
PAINT ORANGE (-1790 2885);
FORCEPROP 2 LASTPIN (-1800 2825) $PN BJ12
J 0
(-1790 2835);
DISPLAY 0.617021 (-1790 2835);
PAINT ORANGE (-1790 2835);
FORCEPROP 2 LASTPIN (-1800 2775) $PN BJ14
J 0
(-1790 2785);
DISPLAY 0.617021 (-1790 2785);
PAINT ORANGE (-1790 2785);
FORCEPROP 2 LASTPIN (-1800 2725) $PN BK13
J 0
(-1790 2735);
DISPLAY 0.617021 (-1790 2735);
PAINT ORANGE (-1790 2735);
FORCEPROP 2 LASTPIN (-1800 2675) $PN BK15
J 0
(-1790 2685);
DISPLAY 0.617021 (-1790 2685);
PAINT ORANGE (-1790 2685);
FORCEPROP 2 LASTPIN (-1800 2625) $PN BL14
J 0
(-1790 2635);
DISPLAY 0.617021 (-1790 2635);
PAINT ORANGE (-1790 2635);
FORCEPROP 1 LAST PACK_TYPE BGA1
J 0
(-3550 4875);
PAINT SKYBLUE (-3550 4875);
DISPLAY INVISIBLE (-3550 4875);
FORCEPROP 2 LAST SEC_TYPE BGA1
J 0
(-3550 4875);
DISPLAY 1.021277 (-3550 4875);
PAINT ORANGE (-3550 4875);
DISPLAY INVISIBLE (-3550 4875);
FORCEPROP 2 LAST CDS_LIB chpset_lib
J 0
(-2700 2575);
PAINT ORANGE (-2700 2575);
DISPLAY INVISIBLE (-2700 2575);
FORCEPROP 2 LAST SEC 21
J 0
(-3550 4875);
DISPLAY 0.680851 (-3550 4875);
PAINT MONO (-3550 4875);
DISPLAY INVISIBLE (-3550 4875);
FORCEPROP 2 LAST CDS_LOCATION U2D1
J 0
(-3550 4825);
DISPLAY 0.617021 (-3550 4825);
PAINT AQUA (-3550 4825);
DISPLAY INVISIBLE (-3550 4825);
FORCEPROP 1 LAST PATH I33
J 0
(-2700 4775);
PAINT GREEN (-2700 4775);
DISPLAY INVISIBLE (-2700 4775);
FORCEADD PVPP_GHJ..1
(-1425 1925);
FORCEPROP 3 LASTPIN (-1425 1875) SIG_NAME PVPP_GHJ\g
J 0
(-1415 1885);
DISPLAY 0.659574 (-1415 1885);
PAINT MONO (-1415 1885);
DISPLAY INVISIBLE (-1415 1885);
FORCEPROP 1 LAST VOLTAGE 2.5V
J 0
(-1470 1882);
DISPLAY 0.340426 (-1470 1882);
PAINT SKYBLUE (-1470 1882);
DISPLAY INVISIBLE (-1470 1882);
FORCEPROP 2 LAST BOM_COST PVPP_KLM_VR
J 0
(-1350 2025);
PAINT MONO (-1350 2025);
DISPLAY INVISIBLE (-1350 2025);
FORCEPROP 2 LAST CDS_LIB mstr_symbols
J 0
(-1425 1925);
PAINT ORANGE (-1425 1925);
DISPLAY INVISIBLE (-1425 1925);
FORCEPROP 1 LAST BODY_TYPE PLUMBING
J 0
(-1470 1882);
DISPLAY 0.340426 (-1470 1882);
PAINT GREEN (-1470 1882);
DISPLAY INVISIBLE (-1470 1882);
FORCEPROP 1 LAST PATH I38
J 0
(-1375 1950);
DISPLAY 0.872340 (-1375 1950);
PAINT AQUA (-1375 1950);
DISPLAY INVISIBLE (-1375 1950);
FORCEPROP 2 LAST ROOM PVPP_KLM_VR
J 0
(-1175 2025);
PAINT ORANGE (-1175 2025);
DISPLAY INVISIBLE (-1175 2025);
FORCEPROP 1 LAST HDL_POWER PVPP_GHJ
J 1
(-1425 1975);
DISPLAY 0.872340 (-1425 1975);
PAINT GREEN (-1425 1975);
DISPLAY INVISIBLE (-1425 1975);
FORCEADD VCC_CORE..1
(-300 1525);
FORCEPROP 3 LASTPIN (-300 1475) SIG_NAME P1V8_MCP_CPU1\g
J 0
(-290 1485);
DISPLAY 0.659574 (-290 1485);
PAINT MONO (-290 1485);
DISPLAY INVISIBLE (-290 1485);
FORCEPROP 1 LAST HDL_POWER P1V8_MCP_CPU1
J 1
(-300 1575);
DISPLAY 0.617021 (-300 1575);
PAINT GREEN (-300 1575);
FORCEPROP 0 LAST VOLTAGE 1.8
J 0
(-300 1675);
DISPLAY 1.021277 (-300 1675);
PAINT SKYBLUE (-300 1675);
DISPLAY INVISIBLE (-300 1675);
FORCEPROP 2 LAST CDS_LIB mstr_symbols
J 0
(-300 1525);
PAINT ORANGE (-300 1525);
DISPLAY INVISIBLE (-300 1525);
FORCEPROP 1 LAST PATH I39
J 0
(-250 1550);
DISPLAY 0.872340 (-250 1550);
PAINT AQUA (-250 1550);
DISPLAY INVISIBLE (-250 1550);
FORCEADD P3V3_STBY..1
(-1150 1200);
FORCEPROP 3 LASTPIN (-1150 1150) SIG_NAME P3V3_STBY\g
J 0
(-1140 1160);
DISPLAY 0.659574 (-1140 1160);
PAINT MONO (-1140 1160);
DISPLAY INVISIBLE (-1140 1160);
FORCEPROP 1 LAST VOLTAGE 3.3V
J 0
(-1195 1157);
DISPLAY 0.340426 (-1195 1157);
PAINT SKYBLUE (-1195 1157);
DISPLAY INVISIBLE (-1195 1157);
FORCEPROP 1 LAST SIZE 1B
J 0
(-1105 1222);
DISPLAY 0.340426 (-1105 1222);
PAINT GREEN (-1105 1222);
DISPLAY INVISIBLE (-1105 1222);
FORCEPROP 2 LAST CDS_LIB mstr_symbols
J 0
(-1150 1200);
PAINT ORANGE (-1150 1200);
DISPLAY INVISIBLE (-1150 1200);
FORCEPROP 1 LAST BODY_TYPE PLUMBING
J 0
(-1195 1157);
DISPLAY 0.340426 (-1195 1157);
PAINT GREEN (-1195 1157);
DISPLAY INVISIBLE (-1195 1157);
FORCEPROP 1 LAST PATH I40
J 0
(-1105 1202);
DISPLAY 0.340426 (-1105 1202);
PAINT GREEN (-1105 1202);
DISPLAY INVISIBLE (-1105 1202);
FORCEPROP 1 LAST HDL_POWER P3V3_STBY
J 0
(-1450 1075);
DISPLAY 0.872340 (-1450 1075);
PAINT ORANGE (-1450 1075);
DISPLAY INVISIBLE (-1450 1075);
FORCEADD PRELIM..10
(-2690 2565);
PAINT GRAY (-2690 2565);
FORCEPROP 2 LAST CDS_LIB mstr_misc
J 0
(-2690 2565);
PAINT ORANGE (-2690 2565);
DISPLAY INVISIBLE (-2690 2565);
FORCEPROP 1 LAST COMMENT_BODY TRUE
J 0
(-2690 2565);
PAINT ORANGE (-2690 2565);
DISPLAY INVISIBLE (-2690 2565);
FORCEADD DESIGN_NOTE..1
(-5575 800);
FORCEPROP 0 LAST L1 CPU SYMBOLS 1-30 ARE PRELIMINARY AND SUBJECT TO CHANGE
J 0
(-5775 675);
DISPLAY 1.021277 (-5775 675);
PAINT ORANGE (-5775 675);
FORCEPROP 2 LAST CDS_LIB mstr_symbols
J 0
(-5575 800);
PAINT ORANGE (-5575 800);
DISPLAY INVISIBLE (-5575 800);
FORCEPROP 1 LAST COMMENT_BODY TRUE
J 0
(-5550 900);
DISPLAY 0.978723 (-5550 900);
PAINT ORANGE (-5550 900);
DISPLAY INVISIBLE (-5550 900);
FORCEADD INTEL_CORP_BPAGE..1
(0 0);
FORCEPROP 1 LAST CDS_CON_LAST_MODIFIED Tue Dec 01 11:51:38 2015
J 0
(-1425 325);
DISPLAY 1.340426 (-1425 325);
PAINT GREEN (-1425 325);
DISPLAY INVISIBLE (-1425 325);
FORCEPROP 1 LAST CUSTOM_TXT_CDS <CURRENT_DESIGN_SHEET> OF <TOTAL_DESIGN_SHEETS>
J 0
(-500 25);
PAINT GREEN (-500 25);
FORCEPROP 1 LAST CUSTOM_TXT_CDS <CON_LAST_MODIFIED>
J 0
(-1925 350);
PAINT GREEN (-1925 350);
FORCEPROP 2 LAST CUSTOM_TXT_CDS <XR_PAGE_TITLE>
J 0
(-7890 5250);
DISPLAY 0.638298 (-7890 5250);
PAINT PINK (-7890 5250);
DISPLAY INVISIBLE (-7890 5250);
FORCEPROP 1 LAST SCH_ADDRESS3 Santa Clara, CA 95052-8119
J 0
(-3975 25);
DISPLAY 0.617021 (-3975 25);
PAINT GREEN (-3975 25);
FORCEPROP 1 LAST SCH_ADDRESS2 P.O. BOX 58119
J 0
(-3975 75);
DISPLAY 0.617021 (-3975 75);
PAINT GREEN (-3975 75);
FORCEPROP 1 LAST SCH_ADDRESS1 2200 Mission College Blvd.
J 0
(-3975 125);
DISPLAY 0.617021 (-3975 125);
PAINT GREEN (-3975 125);
FORCEPROP 1 LAST SCH_TITLE SKYLAKE - SKT1 - 18 OF 21
J 0
(-7950 50);
DISPLAY 1.212766 (-7950 50);
PAINT GREEN (-7950 50);
FORCEPROP 1 LAST SCH_NUMBER H4694802
J 0
(-1300 150);
DISPLAY 1.212766 (-1300 150);
PAINT YELLOW (-1300 150);
FORCEPROP 1 LAST SCH_DEPT BESD
J 1
(-4450 100);
DISPLAY 1.212766 (-4450 100);
PAINT YELLOW (-4450 100);
FORCEPROP 1 LAST SCH_REV 2.420
J 0
(-250 150);
DISPLAY 0.978723 (-250 150);
PAINT YELLOW (-250 150);
FORCEPROP 2 LAST PAGE_BORDER TRUE
J 0
(-7890 5250);
DISPLAY 0.851064 (-7890 5250);
PAINT PINK (-7890 5250);
DISPLAY INVISIBLE (-7890 5250);
FORCEPROP 2 LAST CDS_LIB mstr_symbols
J 0
(0 0);
PAINT ORANGE (0 0);
DISPLAY INVISIBLE (0 0);
FORCEPROP 1 LAST COMMENT_BODY TRUE
J 0
(12 12);
DISPLAY 0.638298 (12 12);
PAINT GREEN (12 12);
DISPLAY INVISIBLE (12 12);
FORCEPROP 2 LAST CDS_XR_PAGE_TITLE CR-72 : @BASEBOARD_FAB2_LIB.BASEBOARD_FAB2(SCH_1):PAGE72
J 0
(-7890 5250);
DISPLAY 0.638298 (-7890 5250);
PAINT PINK (-7890 5250);
DISPLAY INVISIBLE (-7890 5250);
WIRE 16 -1 (-7325 1250)(-7050 1250);
WIRE 16 -1 (-7325 1300)(-7325 1250);
WIRE 16 -1 (-7325 1300)(-7050 1300);
WIRE 16 -1 (-7325 1350)(-7325 1300);
WIRE 16 -1 (-7325 1350)(-7050 1350);
WIRE 16 -1 (-7325 1450)(-7325 1350);
WIRE 16 -1 (-7325 1450)(-7050 1450);
WIRE 16 -1 (-7325 1500)(-7325 1450);
WIRE 16 -1 (-7325 1500)(-7050 1500);
WIRE 16 -1 (-7325 1550)(-7325 1500);
WIRE 16 -1 (-7325 1550)(-7050 1550);
WIRE 16 -1 (-7325 1600)(-7325 1550);
WIRE 16 -1 (-7325 1600)(-7050 1600);
WIRE 16 -1 (-7325 1650)(-7325 1600);
WIRE 16 -1 (-7325 1650)(-7050 1650);
WIRE 16 -1 (-7325 1700)(-7325 1650);
WIRE 16 -1 (-7325 1700)(-7050 1700);
WIRE 16 -1 (-7325 1750)(-7325 1700);
WIRE 16 -1 (-7325 1750)(-7050 1750);
WIRE 16 -1 (-7325 1800)(-7325 1750);
WIRE 16 -1 (-7325 1800)(-7050 1800);
WIRE 16 -1 (-7325 1850)(-7325 1800);
WIRE 16 -1 (-7325 1850)(-7050 1850);
WIRE 16 -1 (-7325 1900)(-7325 1850);
WIRE 16 -1 (-7325 1900)(-7050 1900);
WIRE 16 -1 (-7325 1950)(-7325 1900);
WIRE 16 -1 (-7325 1950)(-7050 1950);
WIRE 16 -1 (-7325 2000)(-7325 1950);
WIRE 16 -1 (-7325 2050)(-7325 2000);
WIRE 16 -1 (-7325 2000)(-7050 2000);
WIRE 16 -1 (-7325 2050)(-7050 2050);
WIRE 16 -1 (-7325 2100)(-7325 2050);
WIRE 16 -1 (-7325 2100)(-7050 2100);
WIRE 16 -1 (-7325 2150)(-7325 2100);
WIRE 16 -1 (-7325 2150)(-7050 2150);
WIRE 16 -1 (-7325 2200)(-7325 2150);
WIRE 16 -1 (-7325 2200)(-7050 2200);
WIRE 16 -1 (-7325 2250)(-7325 2200);
WIRE 16 -1 (-7325 2250)(-7050 2250);
WIRE 16 -1 (-7325 2300)(-7325 2250);
WIRE 16 -1 (-7325 2300)(-7050 2300);
WIRE 16 -1 (-7325 2350)(-7325 2300);
WIRE 16 -1 (-7325 2350)(-7050 2350);
WIRE 16 -1 (-7325 2400)(-7325 2350);
WIRE 16 -1 (-7325 2400)(-7050 2400);
WIRE 16 -1 (-7325 2450)(-7325 2400);
WIRE 16 -1 (-7325 2450)(-7050 2450);
WIRE 16 -1 (-7325 2500)(-7325 2450);
WIRE 16 -1 (-7325 2500)(-7050 2500);
WIRE 16 -1 (-7325 2550)(-7325 2500);
WIRE 16 -1 (-7325 2550)(-7050 2550);
WIRE 16 -1 (-7325 2600)(-7325 2550);
WIRE 16 -1 (-7325 2600)(-7050 2600);
WIRE 16 -1 (-7325 2650)(-7325 2600);
WIRE 16 -1 (-7325 2650)(-7050 2650);
WIRE 16 -1 (-7325 2700)(-7325 2650);
WIRE 16 -1 (-7325 2700)(-7050 2700);
WIRE 16 -1 (-7325 2750)(-7325 2700);
WIRE 16 -1 (-7325 2750)(-7050 2750);
WIRE 16 -1 (-7325 2800)(-7325 2750);
WIRE 16 -1 (-7325 2800)(-7050 2800);
WIRE 16 -1 (-7325 2850)(-7325 2800);
WIRE 16 -1 (-7325 2850)(-7050 2850);
WIRE 16 -1 (-7325 2900)(-7325 2850);
WIRE 16 -1 (-7325 2900)(-7050 2900);
WIRE 16 -1 (-7325 2950)(-7325 2900);
WIRE 16 -1 (-7325 2950)(-7050 2950);
WIRE 16 -1 (-7325 3000)(-7325 2950);
WIRE 16 -1 (-7325 3000)(-7050 3000);
WIRE 16 -1 (-7325 3050)(-7325 3000);
WIRE 16 -1 (-7325 3050)(-7050 3050);
WIRE 16 -1 (-7325 3100)(-7325 3050);
WIRE 16 -1 (-7325 3100)(-7050 3100);
WIRE 16 -1 (-7325 3150)(-7325 3100);
WIRE 16 -1 (-7325 3150)(-7050 3150);
WIRE 16 -1 (-7325 3200)(-7325 3150);
WIRE 16 -1 (-7325 3200)(-7050 3200);
WIRE 16 -1 (-7325 3250)(-7325 3200);
WIRE 16 -1 (-7325 3250)(-7050 3250);
WIRE 16 -1 (-7325 3300)(-7325 3250);
WIRE 16 -1 (-7325 3300)(-7050 3300);
WIRE 16 -1 (-7325 3350)(-7325 3300);
WIRE 16 -1 (-7325 3350)(-7050 3350);
WIRE 16 -1 (-7325 3400)(-7325 3350);
WIRE 16 -1 (-7325 3400)(-7050 3400);
WIRE 16 -1 (-7325 3450)(-7325 3400);
WIRE 16 -1 (-7325 3450)(-7050 3450);
WIRE 16 -1 (-7325 3500)(-7325 3450);
WIRE 16 -1 (-7325 3500)(-7050 3500);
WIRE 16 -1 (-7325 3550)(-7325 3500);
WIRE 16 -1 (-7325 3550)(-7050 3550);
WIRE 16 -1 (-7325 3600)(-7325 3550);
WIRE 16 -1 (-7325 3600)(-7050 3600);
WIRE 16 -1 (-7325 3650)(-7325 3600);
WIRE 16 -1 (-7325 3650)(-7050 3650);
WIRE 16 -1 (-7325 3700)(-7325 3650);
WIRE 16 -1 (-7325 3700)(-7050 3700);
WIRE 16 -1 (-7325 3750)(-7325 3700);
WIRE 16 -1 (-7325 3750)(-7050 3750);
WIRE 16 -1 (-7325 3800)(-7325 3750);
WIRE 16 -1 (-7325 3800)(-7050 3800);
WIRE 16 -1 (-7325 3850)(-7325 3800);
WIRE 16 -1 (-7325 3850)(-7325 4200);
WIRE 16 -1 (-7325 3850)(-7050 3850);
WIRE 16 -1 (-5050 1350)(-5050 1300);
WIRE 16 -1 (-5050 1450)(-5050 1350);
WIRE 16 -1 (-5050 1350)(-5350 1350);
WIRE 16 -1 (-5050 1300)(-5350 1300);
WIRE 16 -1 (-5050 1500)(-5050 1450);
WIRE 16 -1 (-5050 1450)(-5350 1450);
WIRE 16 -1 (-5050 1550)(-5050 1500);
WIRE 16 -1 (-5050 1500)(-5350 1500);
WIRE 16 -1 (-5050 1600)(-5050 1550);
WIRE 16 -1 (-5050 1550)(-5350 1550);
WIRE 16 -1 (-5050 1650)(-5050 1600);
WIRE 16 -1 (-5050 1600)(-5350 1600);
WIRE 16 -1 (-5050 1700)(-5050 1650);
WIRE 16 -1 (-5050 1650)(-5350 1650);
WIRE 16 -1 (-5050 1750)(-5050 1700);
WIRE 16 -1 (-5050 1700)(-5350 1700);
WIRE 16 -1 (-5050 1800)(-5050 1750);
WIRE 16 -1 (-5050 1750)(-5350 1750);
WIRE 16 -1 (-5050 1850)(-5050 1800);
WIRE 16 -1 (-5050 1800)(-5350 1800);
WIRE 16 -1 (-5050 1900)(-5050 1850);
WIRE 16 -1 (-5050 1850)(-5350 1850);
WIRE 16 -1 (-5050 1950)(-5050 1900);
WIRE 16 -1 (-5050 1900)(-5350 1900);
WIRE 16 -1 (-5050 2000)(-5050 1950);
WIRE 16 -1 (-5050 1950)(-5350 1950);
WIRE 16 -1 (-5050 2050)(-5050 2000);
WIRE 16 -1 (-5050 2000)(-5350 2000);
WIRE 16 -1 (-5050 2100)(-5050 2050);
WIRE 16 -1 (-5050 2050)(-5350 2050);
WIRE 16 -1 (-5050 2150)(-5050 2100);
WIRE 16 -1 (-5050 2100)(-5350 2100);
WIRE 16 -1 (-5050 2200)(-5050 2150);
WIRE 16 -1 (-5050 2150)(-5350 2150);
WIRE 16 -1 (-5050 2250)(-5050 2200);
WIRE 16 -1 (-5050 2200)(-5350 2200);
WIRE 16 -1 (-5050 2300)(-5050 2250);
WIRE 16 -1 (-5050 2250)(-5350 2250);
WIRE 16 -1 (-5050 2350)(-5050 2300);
WIRE 16 -1 (-5050 2300)(-5350 2300);
WIRE 16 -1 (-5050 2400)(-5050 2350);
WIRE 16 -1 (-5050 2350)(-5350 2350);
WIRE 16 -1 (-5050 2450)(-5050 2400);
WIRE 16 -1 (-5050 2400)(-5350 2400);
WIRE 16 -1 (-5050 2500)(-5050 2450);
WIRE 16 -1 (-5050 2450)(-5350 2450);
WIRE 16 -1 (-5050 2550)(-5050 2500);
WIRE 16 -1 (-5050 2500)(-5350 2500);
WIRE 16 -1 (-5050 2600)(-5050 2550);
WIRE 16 -1 (-5050 2550)(-5350 2550);
WIRE 16 -1 (-5050 2650)(-5050 2600);
WIRE 16 -1 (-5050 2600)(-5350 2600);
WIRE 16 -1 (-5050 2700)(-5050 2650);
WIRE 16 -1 (-5050 2650)(-5350 2650);
WIRE 16 -1 (-5050 2750)(-5050 2700);
WIRE 16 -1 (-5050 2700)(-5350 2700);
WIRE 16 -1 (-5050 2800)(-5050 2750);
WIRE 16 -1 (-5050 2750)(-5350 2750);
WIRE 16 -1 (-5050 2850)(-5050 2800);
WIRE 16 -1 (-5050 2800)(-5350 2800);
WIRE 16 -1 (-5050 2900)(-5050 2850);
WIRE 16 -1 (-5050 2850)(-5350 2850);
WIRE 16 -1 (-5050 2950)(-5050 2900);
WIRE 16 -1 (-5050 2900)(-5350 2900);
WIRE 16 -1 (-5050 3000)(-5050 2950);
WIRE 16 -1 (-5050 2950)(-5350 2950);
WIRE 16 -1 (-5050 3050)(-5050 3000);
WIRE 16 -1 (-5050 3000)(-5350 3000);
WIRE 16 -1 (-5050 3100)(-5050 3050);
WIRE 16 -1 (-5050 3050)(-5350 3050);
WIRE 16 -1 (-5050 3150)(-5050 3100);
WIRE 16 -1 (-5050 3100)(-5350 3100);
WIRE 16 -1 (-5050 3200)(-5050 3150);
WIRE 16 -1 (-5050 3150)(-5350 3150);
WIRE 16 -1 (-5050 3250)(-5050 3200);
WIRE 16 -1 (-5050 3200)(-5350 3200);
WIRE 16 -1 (-5050 3300)(-5050 3250);
WIRE 16 -1 (-5050 3250)(-5350 3250);
WIRE 16 -1 (-5050 3350)(-5050 3300);
WIRE 16 -1 (-5050 3300)(-5350 3300);
WIRE 16 -1 (-5050 3400)(-5050 3350);
WIRE 16 -1 (-5050 3350)(-5350 3350);
WIRE 16 -1 (-5050 3450)(-5050 3400);
WIRE 16 -1 (-5050 3400)(-5350 3400);
WIRE 16 -1 (-5050 3500)(-5050 3450);
WIRE 16 -1 (-5050 3450)(-5350 3450);
WIRE 16 -1 (-5050 3550)(-5050 3500);
WIRE 16 -1 (-5050 3500)(-5350 3500);
WIRE 16 -1 (-5050 3600)(-5050 3550);
WIRE 16 -1 (-5050 3550)(-5350 3550);
WIRE 16 -1 (-5050 3650)(-5050 3600);
WIRE 16 -1 (-5050 3600)(-5350 3600);
WIRE 16 -1 (-5050 3700)(-5050 3650);
WIRE 16 -1 (-5050 3650)(-5350 3650);
WIRE 16 -1 (-5050 3750)(-5050 3700);
WIRE 16 -1 (-5050 3700)(-5350 3700);
WIRE 16 -1 (-5050 3800)(-5050 3750);
WIRE 16 -1 (-5050 3750)(-5350 3750);
WIRE 16 -1 (-5050 3850)(-5050 3800);
WIRE 16 -1 (-5050 3800)(-5350 3800);
WIRE 16 -1 (-5050 4200)(-5050 3850);
WIRE 16 -1 (-5050 3850)(-5350 3850);
WIRE 16 -1 (-3600 875)(-3850 875);
WIRE 16 -1 (-3850 875)(-3850 925);
WIRE 16 -1 (-3600 925)(-3850 925);
WIRE 16 -1 (-3850 925)(-3850 975);
WIRE 16 -1 (-3600 975)(-3850 975);
WIRE 16 -1 (-3850 975)(-3850 1025);
WIRE 16 -1 (-3600 1025)(-3850 1025);
WIRE 16 -1 (-3850 1075)(-3850 1025);
WIRE 16 -1 (-3600 1075)(-3850 1075);
WIRE 16 -1 (-3850 1075)(-3850 1125);
WIRE 16 -1 (-3600 1125)(-3850 1125);
WIRE 16 -1 (-3850 1175)(-3850 1125);
WIRE 16 -1 (-3600 1175)(-3850 1175);
WIRE 16 -1 (-3850 1225)(-3850 1175);
WIRE 16 -1 (-3600 1225)(-3850 1225);
WIRE 16 -1 (-3850 1275)(-3850 1225);
WIRE 16 -1 (-3600 1275)(-3850 1275);
WIRE 16 -1 (-3850 1325)(-3850 1275);
WIRE 16 -1 (-3600 1325)(-3850 1325);
WIRE 16 -1 (-3850 1375)(-3850 1325);
WIRE 16 -1 (-3600 1375)(-3850 1375);
WIRE 16 -1 (-3850 1425)(-3850 1375);
WIRE 16 -1 (-3600 1425)(-3850 1425);
WIRE 16 -1 (-3850 1475)(-3850 1425);
WIRE 16 -1 (-3600 1475)(-3850 1475);
WIRE 16 -1 (-3850 1525)(-3850 1475);
WIRE 16 -1 (-3600 1525)(-3850 1525);
WIRE 16 -1 (-3850 1575)(-3850 1525);
WIRE 16 -1 (-3600 1575)(-3850 1575);
WIRE 16 -1 (-3850 1625)(-3850 1575);
WIRE 16 -1 (-3600 1625)(-3850 1625);
WIRE 16 -1 (-3850 1675)(-3850 1625);
WIRE 16 -1 (-3600 1675)(-3850 1675);
WIRE 16 -1 (-3850 1725)(-3850 1675);
WIRE 16 -1 (-3600 1725)(-3850 1725);
WIRE 16 -1 (-3850 1775)(-3850 1725);
WIRE 16 -1 (-3600 1775)(-3850 1775);
WIRE 16 -1 (-3850 1825)(-3850 1775);
WIRE 16 -1 (-3600 1825)(-3850 1825);
WIRE 16 -1 (-3850 1875)(-3850 1825);
WIRE 16 -1 (-3600 1875)(-3850 1875);
WIRE 16 -1 (-3850 1925)(-3850 1875);
WIRE 16 -1 (-3600 1925)(-3850 1925);
WIRE 16 -1 (-3850 1975)(-3850 1925);
WIRE 16 -1 (-3600 1975)(-3850 1975);
WIRE 16 -1 (-3850 2025)(-3850 1975);
WIRE 16 -1 (-3600 2025)(-3850 2025);
WIRE 16 -1 (-3850 2075)(-3850 2025);
WIRE 16 -1 (-3600 2075)(-3850 2075);
WIRE 16 -1 (-3850 2125)(-3850 2075);
WIRE 16 -1 (-3600 2125)(-3850 2125);
WIRE 16 -1 (-3850 2175)(-3850 2125);
WIRE 16 -1 (-3600 2175)(-3850 2175);
WIRE 16 -1 (-3850 2225)(-3850 2175);
WIRE 16 -1 (-3600 2225)(-3850 2225);
WIRE 16 -1 (-3850 2275)(-3850 2225);
WIRE 16 -1 (-3600 2275)(-3850 2275);
WIRE 16 -1 (-3850 2325)(-3850 2275);
WIRE 16 -1 (-3600 2325)(-3850 2325);
WIRE 16 -1 (-3850 2375)(-3850 2325);
WIRE 16 -1 (-3600 2375)(-3850 2375);
WIRE 16 -1 (-3850 2425)(-3850 2375);
WIRE 16 -1 (-3600 2425)(-3850 2425);
WIRE 16 -1 (-3850 2475)(-3850 2425);
WIRE 16 -1 (-3600 2475)(-3850 2475);
WIRE 16 -1 (-3850 2525)(-3850 2475);
WIRE 16 -1 (-3600 2525)(-3850 2525);
WIRE 16 -1 (-3850 2575)(-3850 2525);
WIRE 16 -1 (-3600 2575)(-3850 2575);
WIRE 16 -1 (-3850 2625)(-3850 2575);
WIRE 16 -1 (-3600 2625)(-3850 2625);
WIRE 16 -1 (-3850 2675)(-3850 2625);
WIRE 16 -1 (-3600 2675)(-3850 2675);
WIRE 16 -1 (-3850 2725)(-3850 2675);
WIRE 16 -1 (-3600 2725)(-3850 2725);
WIRE 16 -1 (-3850 2775)(-3850 2725);
WIRE 16 -1 (-3600 2775)(-3850 2775);
WIRE 16 -1 (-3850 2825)(-3850 2775);
WIRE 16 -1 (-3600 2825)(-3850 2825);
WIRE 16 -1 (-3850 2875)(-3850 2825);
WIRE 16 -1 (-3600 2875)(-3850 2875);
WIRE 16 -1 (-3850 2925)(-3850 2875);
WIRE 16 -1 (-3600 2925)(-3850 2925);
WIRE 16 -1 (-3850 2975)(-3850 2925);
WIRE 16 -1 (-3600 2975)(-3850 2975);
WIRE 16 -1 (-3850 3025)(-3850 2975);
WIRE 16 -1 (-3600 3025)(-3850 3025);
WIRE 16 -1 (-3850 3075)(-3850 3025);
WIRE 16 -1 (-3600 3075)(-3850 3075);
WIRE 16 -1 (-3850 3125)(-3850 3075);
WIRE 16 -1 (-3600 3125)(-3850 3125);
WIRE 16 -1 (-3850 3175)(-3850 3125);
WIRE 16 -1 (-3600 3175)(-3850 3175);
WIRE 16 -1 (-3850 3225)(-3850 3175);
WIRE 16 -1 (-3600 3225)(-3850 3225);
WIRE 16 -1 (-3850 3275)(-3850 3225);
WIRE 16 -1 (-3600 3275)(-3850 3275);
WIRE 16 -1 (-3850 3325)(-3850 3275);
WIRE 16 -1 (-3600 3325)(-3850 3325);
WIRE 16 -1 (-3850 3375)(-3850 3325);
WIRE 16 -1 (-3600 3375)(-3850 3375);
WIRE 16 -1 (-3850 3425)(-3850 3375);
WIRE 16 -1 (-3600 3425)(-3850 3425);
WIRE 16 -1 (-3850 3475)(-3850 3425);
WIRE 16 -1 (-3600 3475)(-3850 3475);
WIRE 16 -1 (-3850 3525)(-3850 3475);
WIRE 16 -1 (-3600 3525)(-3850 3525);
WIRE 16 -1 (-3850 3575)(-3850 3525);
WIRE 16 -1 (-3600 3575)(-3850 3575);
WIRE 16 -1 (-3850 3625)(-3850 3575);
WIRE 16 -1 (-3600 3625)(-3850 3625);
WIRE 16 -1 (-3850 3675)(-3850 3625);
WIRE 16 -1 (-3600 3675)(-3850 3675);
WIRE 16 -1 (-3850 3725)(-3850 3675);
WIRE 16 -1 (-3600 3725)(-3850 3725);
WIRE 16 -1 (-3850 3775)(-3850 3725);
WIRE 16 -1 (-3600 3775)(-3850 3775);
WIRE 16 -1 (-3850 3825)(-3850 3775);
WIRE 16 -1 (-3600 3825)(-3850 3825);
WIRE 16 -1 (-3850 3875)(-3850 3825);
WIRE 16 -1 (-3600 3875)(-3850 3875);
WIRE 16 -1 (-3850 3925)(-3850 3875);
WIRE 16 -1 (-3600 3925)(-3850 3925);
WIRE 16 -1 (-3850 3975)(-3850 3925);
WIRE 16 -1 (-3600 3975)(-3850 3975);
WIRE 16 -1 (-3850 4025)(-3850 3975);
WIRE 16 -1 (-3600 4025)(-3850 4025);
WIRE 16 -1 (-3850 4075)(-3850 4025);
WIRE 16 -1 (-3600 4075)(-3850 4075);
WIRE 16 -1 (-3850 4125)(-3850 4075);
WIRE 16 -1 (-3600 4125)(-3850 4125);
WIRE 16 -1 (-3850 4175)(-3850 4125);
WIRE 16 -1 (-3600 4175)(-3850 4175);
WIRE 16 -1 (-3850 4225)(-3850 4175);
WIRE 16 -1 (-3600 4225)(-3850 4225);
WIRE 16 -1 (-3850 4275)(-3850 4225);
WIRE 16 -1 (-3600 4275)(-3850 4275);
WIRE 16 -1 (-3850 4325)(-3850 4275);
WIRE 16 -1 (-3600 4325)(-3850 4325);
WIRE 16 -1 (-3850 4375)(-3850 4325);
WIRE 16 -1 (-3600 4375)(-3850 4375);
WIRE 16 -1 (-3850 4425)(-3850 4375);
WIRE 16 -1 (-3600 4425)(-3850 4425);
WIRE 16 -1 (-3850 4475)(-3850 4425);
WIRE 16 -1 (-3600 4475)(-3850 4475);
WIRE 16 -1 (-3850 4525)(-3850 4475);
WIRE 16 -1 (-3600 4525)(-3850 4525);
WIRE 16 -1 (-3850 4575)(-3850 4525);
WIRE 16 -1 (-3600 4575)(-3850 4575);
WIRE 16 -1 (-3850 4800)(-3850 4575);
WIRE 16 -1 (-1450 575)(-1450 525);
WIRE 16 -1 (-1450 625)(-1450 575);
WIRE 16 -1 (-1450 575)(-1800 575);
WIRE 16 -1 (-1450 525)(-1800 525);
WIRE 16 -1 (-1450 675)(-1450 625);
WIRE 16 -1 (-1450 625)(-1800 625);
WIRE 16 -1 (-1450 775)(-1450 675);
WIRE 16 -1 (-1450 675)(-1800 675);
WIRE 16 -1 (-1450 775)(-1450 825);
WIRE 16 -1 (-1450 775)(-1800 775);
WIRE 16 -1 (-1450 825)(-1450 875);
WIRE 16 -1 (-1450 825)(-1800 825);
WIRE 16 -1 (-1450 875)(-1450 925);
WIRE 16 -1 (-1450 875)(-1800 875);
WIRE 16 -1 (-1450 925)(-1450 950);
WIRE 16 -1 (-1450 925)(-1800 925);
WIRE 16 -1 (-1450 950)(-1450 975);
WIRE 16 -1 (-1450 950)(-900 950);
WIRE 16 -1 (-900 1000)(-900 950);
WIRE 16 -1 (-1450 975)(-1450 1025);
WIRE 16 -1 (-1450 975)(-1800 975);
WIRE 16 -1 (-1450 1025)(-1800 1025);
WIRE 16 -1 (-1800 3325)(-1600 3325);
WIRE 16 -1 (-1600 3325)(-1600 3375);
WIRE 16 -1 (-1800 3375)(-1600 3375);
WIRE 16 -1 (-1600 3375)(-1600 3425);
WIRE 16 -1 (-1800 3425)(-1600 3425);
WIRE 16 -1 (-1600 3425)(-1600 3475);
WIRE 16 -1 (-1800 3475)(-1600 3475);
WIRE 16 -1 (-1600 3475)(-1600 3525);
WIRE 16 -1 (-1800 3525)(-1600 3525);
WIRE 16 -1 (-1600 3525)(-1600 3575);
WIRE 16 -1 (-1800 3575)(-1600 3575);
WIRE 16 -1 (-1600 3575)(-1600 3625);
WIRE 16 -1 (-1800 3625)(-1600 3625);
WIRE 16 -1 (-1600 3625)(-1600 3675);
WIRE 16 -1 (-1800 3675)(-1600 3675);
WIRE 16 -1 (-1600 3675)(-1600 3725);
WIRE 16 -1 (-1800 3725)(-1600 3725);
WIRE 16 -1 (-1600 3725)(-1600 3775);
WIRE 16 -1 (-1800 3775)(-1600 3775);
WIRE 16 -1 (-1600 3775)(-1600 3825);
WIRE 16 -1 (-1800 3825)(-1600 3825);
WIRE 16 -1 (-1600 3825)(-1600 3875);
WIRE 16 -1 (-1800 3875)(-1600 3875);
WIRE 16 -1 (-1600 3875)(-1600 3925);
WIRE 16 -1 (-1800 3925)(-1600 3925);
WIRE 16 -1 (-1600 3925)(-1600 3975);
WIRE 16 -1 (-1800 3975)(-1600 3975);
WIRE 16 -1 (-1600 3975)(-1600 4025);
WIRE 16 -1 (-1800 4025)(-1600 4025);
WIRE 16 -1 (-1600 4025)(-1600 4075);
WIRE 16 -1 (-1800 4075)(-1600 4075);
WIRE 16 -1 (-1600 4075)(-1600 4125);
WIRE 16 -1 (-1800 4125)(-1600 4125);
WIRE 16 -1 (-1600 4125)(-1600 4175);
WIRE 16 -1 (-1800 4175)(-1600 4175);
WIRE 16 -1 (-1600 4175)(-1600 4225);
WIRE 16 -1 (-1800 4225)(-1600 4225);
WIRE 16 -1 (-1600 4225)(-1600 4275);
WIRE 16 -1 (-1800 4275)(-1600 4275);
WIRE 16 -1 (-1600 4275)(-1600 4325);
WIRE 16 -1 (-1800 4325)(-1600 4325);
WIRE 16 -1 (-1600 4325)(-1600 4375);
WIRE 16 -1 (-1800 4375)(-1600 4375);
WIRE 16 -1 (-1600 4375)(-1600 4425);
WIRE 16 -1 (-1800 4425)(-1600 4425);
WIRE 16 -1 (-1600 4425)(-1600 4475);
WIRE 16 -1 (-1800 4475)(-1600 4475);
WIRE 16 -1 (-1600 4525)(-1600 4475);
WIRE 16 -1 (-1800 4525)(-1600 4525);
WIRE 16 -1 (-1600 4575)(-1600 4525);
WIRE 16 -1 (-1800 4575)(-1600 4575);
WIRE 16 -1 (-1600 4775)(-1600 4575);
WIRE 16 -1 (-525 975)(-525 825);
WIRE 16 -1 (-1800 2625)(-1600 2625);
WIRE 16 -1 (-1600 2675)(-1600 2625);
WIRE 16 -1 (-1800 2675)(-1600 2675);
WIRE 16 -1 (-1600 2725)(-1600 2675);
WIRE 16 -1 (-1800 2725)(-1600 2725);
WIRE 16 -1 (-1600 2775)(-1600 2725);
WIRE 16 -1 (-1800 2775)(-1600 2775);
WIRE 16 -1 (-1600 2825)(-1600 2775);
WIRE 16 -1 (-1800 2825)(-1600 2825);
WIRE 16 -1 (-1600 2875)(-1600 2825);
WIRE 16 -1 (-1800 2875)(-1600 2875);
WIRE 16 -1 (-1600 2925)(-1600 2875);
WIRE 16 -1 (-1800 2925)(-1600 2925);
WIRE 16 -1 (-1600 2975)(-1600 2925);
WIRE 16 -1 (-1800 2975)(-1600 2975);
WIRE 16 -1 (-1600 3025)(-1600 2975);
WIRE 16 -1 (-1800 3025)(-1600 3025);
WIRE 16 -1 (-1600 3075)(-1600 3025);
WIRE 16 -1 (-1800 3075)(-1600 3075);
WIRE 16 -1 (-1600 3125)(-1600 3075);
WIRE 16 -1 (-1800 3125)(-1600 3125);
WIRE 16 -1 (-1600 3125)(-1600 3150);
WIRE 16 -1 (-1600 3150)(-1600 3175);
WIRE 16 -1 (-1600 3150)(-1250 3150);
WIRE 16 -1 (-1250 3250)(-1250 3150);
WIRE 16 -1 (-1600 3175)(-1600 3225);
WIRE 16 -1 (-1800 3175)(-1600 3175);
WIRE 16 -1 (-1800 3225)(-1600 3225);
WIRE 16 -1 (-1800 1725)(-1600 1725);
WIRE 16 -1 (-1600 1775)(-1600 1725);
WIRE 16 -1 (-1800 1775)(-1600 1775);
WIRE 16 -1 (-1600 1825)(-1600 1775);
WIRE 16 -1 (-1800 1825)(-1600 1825);
WIRE 16 -1 (-1600 1875)(-1600 1825);
WIRE 16 -1 (-1800 1875)(-1600 1875);
WIRE 16 -1 (-1600 1925)(-1600 1875);
WIRE 16 -1 (-1800 1925)(-1600 1925);
WIRE 16 -1 (-1600 1975)(-1600 1925);
WIRE 16 -1 (-1800 1975)(-1600 1975);
WIRE 16 -1 (-1600 2025)(-1600 1975);
WIRE 16 -1 (-1800 2025)(-1600 2025);
WIRE 16 -1 (-1600 2075)(-1600 2025);
WIRE 16 -1 (-1800 2075)(-1600 2075);
WIRE 16 -1 (-1600 2125)(-1600 2075);
WIRE 16 -1 (-1800 2125)(-1600 2125);
WIRE 16 -1 (-1600 2175)(-1600 2125);
WIRE 16 -1 (-1800 2175)(-1600 2175);
WIRE 16 -1 (-1600 2175)(-1600 2275);
WIRE 16 -1 (-1800 2275)(-1600 2275);
WIRE 16 -1 (-1600 2325)(-1600 2275);
WIRE 16 -1 (-1800 2325)(-1600 2325);
WIRE 16 -1 (-1600 2375)(-1600 2325);
WIRE 16 -1 (-1800 2375)(-1600 2375);
WIRE 16 -1 (-1600 2425)(-1600 2375);
WIRE 16 -1 (-1800 2425)(-1600 2425);
WIRE 16 -1 (-1600 2425)(-1600 2450);
WIRE 16 -1 (-1600 2450)(-1600 2475);
WIRE 16 -1 (-1250 2450)(-1600 2450);
WIRE 16 -1 (-1250 2525)(-1250 2450);
WIRE 16 -1 (-1600 2525)(-1600 2475);
WIRE 16 -1 (-1800 2475)(-1600 2475);
WIRE 16 -1 (-1800 2525)(-1600 2525);
WIRE 16 -1 (-1800 1475)(-1425 1475);
WIRE 16 -1 (-1425 1475)(-1425 1525);
WIRE 16 -1 (-1800 1525)(-1425 1525);
WIRE 16 -1 (-1425 1525)(-1425 1575);
WIRE 16 -1 (-1800 1575)(-1425 1575);
WIRE 16 -1 (-1425 1575)(-1425 1625);
WIRE 16 -1 (-1800 1625)(-1425 1625);
WIRE 16 -1 (-1425 1625)(-1425 1875);
WIRE 16 -1 (-1450 1275)(-1450 1225);
WIRE 16 -1 (-1800 1275)(-1450 1275);
WIRE 16 -1 (-1450 1275)(-1450 1300);
WIRE 16 -1 (-1450 1225)(-1800 1225);
WIRE 16 -1 (-1450 1300)(-1450 1325);
WIRE 16 -1 (-1450 1300)(-525 1300);
WIRE 16 -1 (-525 1175)(-525 1300);
WIRE 16 -1 (-525 1300)(-300 1300);
WIRE 16 -1 (-1450 1325)(-1450 1375);
WIRE 16 -1 (-1450 1325)(-1800 1325);
WIRE 16 -1 (-1450 1375)(-1800 1375);
WIRE 16 -1 (-300 1475)(-300 1300);
WIRE 16 -1 (-1150 1150)(-1150 1125);
WIRE 16 -1 (-1150 1125)(-1800 1125);
DOT 1 (-525 1300);
DOT 1 (-1450 1300);
DOT 1 (-1450 1275);
DOT 1 (-3850 3225);
DOT 1 (-1600 1925);
DOT 1 (-1600 1775);
DOT 1 (-1425 1575);
DOT 1 (-1425 1525);
DOT 1 (-1425 1625);
DOT 1 (-1450 1325);
DOT 1 (-7325 3550);
DOT 1 (-1450 925);
DOT 1 (-1450 950);
DOT 1 (-1600 2425);
DOT 1 (-1450 975);
DOT 1 (-1600 3150);
DOT 1 (-1600 3125);
DOT 1 (-5050 3850);
DOT 1 (-3850 1525);
DOT 1 (-7325 2450);
DOT 1 (-1600 2475);
DOT 1 (-7325 3150);
DOT 1 (-1450 575);
DOT 1 (-1450 625);
DOT 1 (-5050 1350);
DOT 1 (-1450 675);
DOT 1 (-1450 775);
DOT 1 (-1450 875);
DOT 1 (-1450 825);
DOT 1 (-3850 2525);
DOT 1 (-1600 1825);
DOT 1 (-1600 2125);
DOT 1 (-1600 2175);
DOT 1 (-1600 3175);
DOT 1 (-1600 2675);
DOT 1 (-1600 2725);
DOT 1 (-3850 1475);
DOT 1 (-3850 1175);
DOT 1 (-3850 1575);
DOT 1 (-3850 1975);
DOT 1 (-3850 2325);
DOT 1 (-3850 1925);
DOT 1 (-3850 1125);
DOT 1 (-3850 1075);
DOT 1 (-3850 1025);
DOT 1 (-3850 975);
DOT 1 (-3850 925);
DOT 1 (-3850 4575);
DOT 1 (-3850 4525);
DOT 1 (-1600 4575);
DOT 1 (-1600 4525);
DOT 1 (-1600 4475);
DOT 1 (-1600 4175);
DOT 1 (-1600 4425);
DOT 1 (-1600 4375);
DOT 1 (-1600 4325);
DOT 1 (-1600 4275);
DOT 1 (-1600 4225);
DOT 1 (-1600 4125);
DOT 1 (-3850 4475);
DOT 1 (-3850 4425);
DOT 1 (-3850 4375);
DOT 1 (-3850 4225);
DOT 1 (-3850 4275);
DOT 1 (-3850 4325);
DOT 1 (-3850 4125);
DOT 1 (-3850 4175);
DOT 1 (-3850 4075);
DOT 1 (-1600 4075);
DOT 1 (-1600 4025);
DOT 1 (-1600 3975);
DOT 1 (-1600 3875);
DOT 1 (-1600 3925);
DOT 1 (-1600 3825);
DOT 1 (-1600 3775);
DOT 1 (-1600 3725);
DOT 1 (-1600 3625);
DOT 1 (-1600 3675);
DOT 1 (-1600 3575);
DOT 1 (-1600 3525);
DOT 1 (-1600 3475);
DOT 1 (-1600 3375);
DOT 1 (-1600 3425);
DOT 1 (-1600 3075);
DOT 1 (-1600 2975);
DOT 1 (-1600 3025);
DOT 1 (-1600 2925);
DOT 1 (-1600 2875);
DOT 1 (-1600 2825);
DOT 1 (-1600 2775);
DOT 1 (-1600 2325);
DOT 1 (-1600 2275);
DOT 1 (-1600 1875);
DOT 1 (-3850 4025);
DOT 1 (-3850 3975);
DOT 1 (-3850 3875);
DOT 1 (-3850 3825);
DOT 1 (-3850 3775);
DOT 1 (-3850 3725);
DOT 1 (-3850 3575);
DOT 1 (-3850 3525);
DOT 1 (-3850 3475);
DOT 1 (-3850 3375);
DOT 1 (-3850 3425);
DOT 1 (-3850 3325);
DOT 1 (-3850 3275);
DOT 1 (-3850 3125);
DOT 1 (-3850 3175);
DOT 1 (-3850 3075);
DOT 1 (-3850 2975);
DOT 1 (-3850 3025);
DOT 1 (-3850 2925);
DOT 1 (-3850 2875);
DOT 1 (-3850 2725);
DOT 1 (-3850 2675);
DOT 1 (-3850 2625);
DOT 1 (-3850 2425);
DOT 1 (-3850 2475);
DOT 1 (-3850 2375);
DOT 1 (-3850 2175);
DOT 1 (-3850 2225);
DOT 1 (-3850 2275);
DOT 1 (-3850 2075);
DOT 1 (-3850 2125);
DOT 1 (-3850 2025);
DOT 1 (-3850 1825);
DOT 1 (-3850 1875);
DOT 1 (-3850 1775);
DOT 1 (-3850 1725);
DOT 1 (-3850 1675);
DOT 1 (-3850 1625);
DOT 1 (-3850 1425);
DOT 1 (-3850 1325);
DOT 1 (-3850 1275);
DOT 1 (-3850 1375);
DOT 1 (-3850 1225);
DOT 1 (-7325 1300);
DOT 1 (-7325 1350);
DOT 1 (-7325 1500);
DOT 1 (-7325 1450);
DOT 1 (-7325 1550);
DOT 1 (-7325 1600);
DOT 1 (-7325 1650);
DOT 1 (-7325 1700);
DOT 1 (-7325 1750);
DOT 1 (-7325 1800);
DOT 1 (-7325 1850);
DOT 1 (-7325 1900);
DOT 1 (-7325 1950);
DOT 1 (-7325 2000);
DOT 1 (-7325 2050);
DOT 1 (-7325 2150);
DOT 1 (-7325 2100);
DOT 1 (-7325 2200);
DOT 1 (-7325 2250);
DOT 1 (-7325 2300);
DOT 1 (-7325 2400);
DOT 1 (-7325 2350);
DOT 1 (-7325 2500);
DOT 1 (-7325 2550);
DOT 1 (-7325 2650);
DOT 1 (-7325 2700);
DOT 1 (-7325 2750);
DOT 1 (-7325 2800);
DOT 1 (-7325 2850);
DOT 1 (-7325 2900);
DOT 1 (-7325 2950);
DOT 1 (-7325 3000);
DOT 1 (-7325 3050);
DOT 1 (-7325 3100);
DOT 1 (-7325 3200);
DOT 1 (-7325 3300);
DOT 1 (-7325 3250);
DOT 1 (-7325 3350);
DOT 1 (-7325 3400);
DOT 1 (-7325 3450);
DOT 1 (-7325 3500);
DOT 1 (-7325 3600);
DOT 1 (-7325 3650);
DOT 1 (-7325 3700);
DOT 1 (-7325 3750);
DOT 1 (-7325 3800);
DOT 1 (-7325 3850);
DOT 1 (-5050 1650);
DOT 1 (-5050 1600);
DOT 1 (-5050 1750);
DOT 1 (-5050 1800);
DOT 1 (-5050 1900);
DOT 1 (-5050 1850);
DOT 1 (-5050 1700);
DOT 1 (-5050 2000);
DOT 1 (-5050 2050);
DOT 1 (-5050 2100);
DOT 1 (-5050 2150);
DOT 1 (-5050 1950);
DOT 1 (-5050 2300);
DOT 1 (-5050 2250);
DOT 1 (-5050 2350);
DOT 1 (-5050 2400);
DOT 1 (-5050 2200);
DOT 1 (-5050 2550);
DOT 1 (-5050 2500);
DOT 1 (-5050 2600);
DOT 1 (-5050 2650);
DOT 1 (-5050 2450);
DOT 1 (-5050 2700);
DOT 1 (-5050 2800);
DOT 1 (-5050 2750);
DOT 1 (-5050 2850);
DOT 1 (-5050 2900);
DOT 1 (-5050 2950);
DOT 1 (-5050 3050);
DOT 1 (-5050 3000);
DOT 1 (-5050 3200);
DOT 1 (-5050 3150);
DOT 1 (-5050 3100);
DOT 1 (-5050 3350);
DOT 1 (-5050 3450);
DOT 1 (-5050 3400);
DOT 1 (-5050 3250);
DOT 1 (-5050 3550);
DOT 1 (-5050 3600);
DOT 1 (-5050 3700);
DOT 1 (-5050 3650);
DOT 1 (-5050 3500);
DOT 1 (-5050 3800);
DOT 1 (-5050 3750);
DOT 1 (-3850 3925);
DOT 1 (-5050 1550);
DOT 1 (-5050 1500);
DOT 1 (-5050 1450);
DOT 1 (-3850 2775);
DOT 1 (-3850 2825);
DOT 1 (-1600 2025);
DOT 1 (-1600 2075);
DOT 1 (-1600 2375);
DOT 1 (-1600 1975);
DOT 1 (-3850 2575);
DOT 1 (-3850 3675);
DOT 1 (-7325 2600);
DOT 1 (-5050 3300);
DOT 1 (-3850 3625);
DOT 1 (-1600 2450);
FORCENOTE
BOM_COST=PROC_SOCKET
(-7950 200) 0;
DISPLAY LEFT (-7950 200);
DISPLAY 1.723404 (-7950 200);
PAINT PURPLE (-7950 200);
FORCENOTE
ROOM=CPU1
(-7950 325) 0;
DISPLAY LEFT (-7950 325);
DISPLAY 1.723404 (-7950 325);
PAINT PURPLE (-7950 325);
QUIT
